G04 ================== begin FILE IDENTIFICATION RECORD ==================*
G04 Layout Name:  12433-1M.brd*
G04 Film Name:    L2GND*
G04 File Format:  Gerber RS274X*
G04 File Origin:  Cadence Allegro 16.2-S037*
G04 Origin Date:  Fri Dec 07 18:55:12 2012*
G04 *
G04 Layer:  VIA CLASS/L2GND*
G04 Layer:  PIN/L2GND*
G04 Layer:  ETCH/L2GND*
G04 Layer:  DRAWING FORMAT/LAYER_PCB_STORY*
G04 Layer:  DRAWING FORMAT/LAYER_L2GND*
G04 *
G04 Offset:    (0.00 0.00)*
G04 Mirror:    No*
G04 Mode:      Negative*
G04 Rotation:  0*
G04 FullContactRelief:  No*
G04 UndefLineWidth:     6.00*
G04 ================== end FILE IDENTIFICATION RECORD ====================*
%FSLAX35Y35*MOIN*%
%IR0*IPPOS*OFA0.00000B0.00000*MIA0B0*SFA1.00000B1.00000*%
%AMMACRO30*
4,1,17,-.09386,.06558,
-.103822,.048285,
-.110629,.029523,
-.114075,.009864,
-.114055,-.010095,
-.110569,-.029747,
-.103724,-.048495,
-.09386,-.06558,
-.09745,-.06917,
-.107981,-.051197,
-.115231,-.031669,
-.118979,-.011178,
-.119113,.009652,
-.115627,.030189,
-.108628,.049809,
-.098328,.067916,
-.09745,.06917,
-.09386,.06558,
90.*
4,1,17,-.06558,-.09386,
-.048285,-.103822,
-.029523,-.110629,
-.009864,-.114075,
.010095,-.114055,
.029747,-.110569,
.048495,-.103724,
.06558,-.09386,
.06917,-.09745,
.051197,-.107981,
.031669,-.115231,
.011178,-.118979,
-.009652,-.119113,
-.030189,-.115627,
-.049809,-.108628,
-.067916,-.098328,
-.06917,-.09745,
-.06558,-.09386,
90.*
4,1,17,.09386,-.06558,
.103822,-.048285,
.110629,-.029523,
.114075,-.009864,
.114055,.010095,
.110569,.029747,
.103724,.048495,
.09386,.06558,
.09745,.06917,
.107981,.051197,
.115231,.031669,
.118979,.011178,
.119113,-.009652,
.115627,-.030189,
.108628,-.049809,
.098328,-.067916,
.09745,-.06917,
.09386,-.06558,
90.*
4,1,17,.06558,.09386,
.048285,.103822,
.029523,.110629,
.009864,.114075,
-.010095,.114055,
-.029747,.110569,
-.048495,.103724,
-.06558,.09386,
-.06917,.09745,
-.051197,.107981,
-.031669,.115231,
-.011178,.118979,
.009652,.119113,
.030189,.115627,
.049809,.108628,
.067916,.098328,
.06917,.09745,
.06558,.09386,
90.*
%
%ADD30MACRO30*%
%AMMACRO19*
4,1,16,.07183,.04355,
.078301,.030415,
.082393,.016356,
.083982,.0018,
.083018,-.01281,
.079533,-.027032,
.07363,-.040432,
.07183,-.04355,
.07547,-.04718,
.082516,-.033358,
.087055,-.018522,
.088949,-.003124,
.08814,.012369,
.084653,.027487,
.078594,.041769,
.07547,.04718,
.07183,.04355,
0.0*
4,1,16,.04355,-.07183,
.030415,-.078301,
.016356,-.082393,
.0018,-.083982,
-.01281,-.083018,
-.027032,-.079533,
-.040432,-.07363,
-.04355,-.07183,
-.04718,-.07547,
-.033358,-.082516,
-.018522,-.087055,
-.003124,-.088949,
.012369,-.08814,
.027487,-.084653,
.041769,-.078594,
.04718,-.07547,
.04355,-.07183,
0.0*
4,1,16,-.07183,-.04355,
-.078301,-.030415,
-.082393,-.016356,
-.083982,-.0018,
-.083018,.01281,
-.079533,.027032,
-.07363,.040432,
-.07183,.04355,
-.07547,.04718,
-.082516,.033358,
-.087055,.018522,
-.088949,.003124,
-.08814,-.012369,
-.084653,-.027487,
-.078594,-.041769,
-.07547,-.04718,
-.07183,-.04355,
0.0*
4,1,16,-.04355,.07183,
-.030415,.078301,
-.016356,.082393,
-.0018,.083982,
.01281,.083018,
.027032,.079533,
.040432,.07363,
.04355,.07183,
.04718,.07547,
.033358,.082516,
.018522,.087055,
.003124,.088949,
-.012369,.08814,
-.027487,.084653,
-.041769,.078594,
-.04718,.07547,
-.04355,.07183,
0.0*
%
%ADD19MACRO19*%
%AMMACRO15*
4,1,16,.07909,.0508,
.08671,.036294,
.091695,.020686,
.093894,.004449,
.09324,-.011923,
.089753,-.027933,
.083539,-.043094,
.07909,-.0508,
.0827,-.05442,
.090894,-.039233,
.096325,-.022853,
.09883,-.005779,
.098332,.01147,
.094847,.028371,
.088479,.04441,
.0827,.05442,
.07909,.0508,
0.0*
4,1,16,.0508,-.07909,
.036294,-.08671,
.020686,-.091695,
.004449,-.093894,
-.011923,-.09324,
-.027933,-.089753,
-.043094,-.083539,
-.0508,-.07909,
-.05442,-.0827,
-.039233,-.090894,
-.022853,-.096325,
-.005779,-.09883,
.01147,-.098332,
.028371,-.094847,
.04441,-.088479,
.05442,-.0827,
.0508,-.07909,
0.0*
4,1,16,-.07909,-.0508,
-.08671,-.036294,
-.091695,-.020686,
-.093894,-.004449,
-.09324,.011923,
-.089753,.027933,
-.083539,.043094,
-.07909,.0508,
-.0827,.05442,
-.090894,.039233,
-.096325,.022853,
-.09883,.005779,
-.098332,-.01147,
-.094847,-.028371,
-.088479,-.04441,
-.0827,-.05442,
-.07909,-.0508,
0.0*
4,1,16,-.0508,.07909,
-.036294,.08671,
-.020686,.091695,
-.004449,.093894,
.011923,.09324,
.027933,.089753,
.043094,.083539,
.0508,.07909,
.05442,.0827,
.039233,.090894,
.022853,.096325,
.005779,.09883,
-.01147,.098332,
-.028371,.094847,
-.04441,.088479,
-.05442,.0827,
-.0508,.07909,
0.0*
%
%ADD15MACRO15*%
%ADD18C,.032*%
%ADD17C,.036*%
%ADD16C,.063*%
%ADD13C,.068*%
%ADD25C,.069*%
%AMMACRO20*
4,1,15,.00398,.00044,
.003999,.000208,
.004004,-.000025,
.003996,-.000258,
.00398,-.00044,
.00483,-.00129,
.004897,-.001007,
.004947,-.000721,
.004981,-.000432,
.004997,-.000141,
.004997,.000149,
.00498,.00044,
.004946,.000729,
.004895,.001015,
.00483,.00129,
.00398,.00044,
90.*
4,1,15,.00044,-.00398,
.000208,-.003999,
-.000025,-.004004,
-.000258,-.003996,
-.00044,-.00398,
-.00129,-.00483,
-.001007,-.004897,
-.000721,-.004947,
-.000432,-.004981,
-.000141,-.004997,
.000149,-.004997,
.00044,-.00498,
.000729,-.004946,
.001015,-.004895,
.00129,-.00483,
.00044,-.00398,
90.*
4,1,15,-.00398,-.00044,
-.003999,-.000208,
-.004004,.000025,
-.003996,.000258,
-.00398,.00044,
-.00483,.00129,
-.004897,.001007,
-.004947,.000721,
-.004981,.000432,
-.004997,.000141,
-.004997,-.000149,
-.00498,-.00044,
-.004946,-.000729,
-.004895,-.001015,
-.00483,-.00129,
-.00398,-.00044,
90.*
4,1,15,-.00044,.00398,
-.000208,.003999,
.000025,.004004,
.000258,.003996,
.00044,.00398,
.00129,.00483,
.001007,.004897,
.000721,.004947,
.000432,.004981,
.000141,.004997,
-.000149,.004997,
-.00044,.00498,
-.000729,.004946,
-.001015,.004895,
-.00129,.00483,
-.00044,.00398,
90.*
%
%ADD20MACRO20*%
%AMMACRO12*
4,1,15,.00398,.00044,
.003999,.000208,
.004004,-.000025,
.003996,-.000258,
.00398,-.00044,
.00483,-.00129,
.004897,-.001007,
.004947,-.000721,
.004981,-.000432,
.004997,-.000141,
.004997,.000149,
.00498,.00044,
.004946,.000729,
.004895,.001015,
.00483,.00129,
.00398,.00044,
0.0*
4,1,15,.00044,-.00398,
.000208,-.003999,
-.000025,-.004004,
-.000258,-.003996,
-.00044,-.00398,
-.00129,-.00483,
-.001007,-.004897,
-.000721,-.004947,
-.000432,-.004981,
-.000141,-.004997,
.000149,-.004997,
.00044,-.00498,
.000729,-.004946,
.001015,-.004895,
.00129,-.00483,
.00044,-.00398,
0.0*
4,1,15,-.00398,-.00044,
-.003999,-.000208,
-.004004,.000025,
-.003996,.000258,
-.00398,.00044,
-.00483,.00129,
-.004897,.001007,
-.004947,.000721,
-.004981,.000432,
-.004997,.000141,
-.004997,-.000149,
-.00498,-.00044,
-.004946,-.000729,
-.004895,-.001015,
-.00483,-.00129,
-.00398,-.00044,
0.0*
4,1,15,-.00044,.00398,
-.000208,.003999,
.000025,.004004,
.000258,.003996,
.00044,.00398,
.00129,.00483,
.001007,.004897,
.000721,.004947,
.000432,.004981,
.000141,.004997,
-.000149,.004997,
-.00044,.00498,
-.000729,.004946,
-.001015,.004895,
-.00129,.00483,
-.00044,.00398,
0.0*
%
%ADD12MACRO12*%
%AMMACRO14*
4,1,13,.02632,.01218,
.028035,.007425,
.028899,.002443,
.028884,-.002612,
.027991,-.007588,
.02632,-.01218,
.03005,-.01591,
.032356,-.01045,
.033679,-.004673,
.033979,.001247,
.033246,.007128,
.031504,.012793,
.03005,.01591,
.02632,.01218,
270.*
4,1,13,.01218,-.02632,
.007425,-.028035,
.002443,-.028899,
-.002612,-.028884,
-.007588,-.027991,
-.01218,-.02632,
-.01591,-.03005,
-.01045,-.032356,
-.004673,-.033679,
.001247,-.033979,
.007128,-.033246,
.012793,-.031504,
.01591,-.03005,
.01218,-.02632,
270.*
4,1,13,-.02632,-.01218,
-.028035,-.007425,
-.028899,-.002443,
-.028884,.002612,
-.027991,.007588,
-.02632,.01218,
-.03005,.01591,
-.032356,.01045,
-.033679,.004673,
-.033979,-.001247,
-.033246,-.007128,
-.031504,-.012793,
-.03005,-.01591,
-.02632,-.01218,
270.*
4,1,13,-.01218,.02632,
-.007425,.028035,
-.002443,.028899,
.002612,.028884,
.007588,.027991,
.01218,.02632,
.01591,.03005,
.01045,.032356,
.004673,.033679,
-.001247,.033979,
-.007128,.033246,
-.012793,.031504,
-.01591,.03005,
-.01218,.02632,
270.*
%
%ADD14MACRO14*%
%AMMACRO24*
4,1,14,.0267,.01255,
.028474,.007723,
.029382,.002661,
.029398,-.002481,
.02852,-.007549,
.026776,-.012386,
.0267,-.01255,
.03042,-.01628,
.032785,-.01075,
.034154,-.004894,
.034484,.001111,
.033768,.007082,
.032025,.012838,
.03042,.01628,
.0267,.01255,
270.*
4,1,14,.01255,-.0267,
.007723,-.028474,
.002661,-.029382,
-.002481,-.029398,
-.007549,-.02852,
-.012386,-.026776,
-.01255,-.0267,
-.01628,-.03042,
-.01075,-.032785,
-.004894,-.034154,
.001111,-.034484,
.007082,-.033768,
.012838,-.032025,
.01628,-.03042,
.01255,-.0267,
270.*
4,1,14,-.0267,-.01255,
-.028474,-.007723,
-.029382,-.002661,
-.029398,.002481,
-.02852,.007549,
-.026776,.012386,
-.0267,.01255,
-.03042,.01628,
-.032785,.01075,
-.034154,.004894,
-.034484,-.001111,
-.033768,-.007082,
-.032025,-.012838,
-.03042,-.01628,
-.0267,-.01255,
270.*
4,1,14,-.01255,.0267,
-.007723,.028474,
-.002661,.029382,
.002481,.029398,
.007549,.02852,
.012386,.026776,
.01255,.0267,
.01628,.03042,
.01075,.032785,
.004894,.034154,
-.001111,.034484,
-.007082,.033768,
-.012838,.032025,
-.01628,.03042,
-.01255,.0267,
270.*
%
%ADD24MACRO24*%
%ADD21C,.143*%
%ADD11C,.17*%
%ADD23C,.127*%
%ADD22C,.154*%
%AMMACRO29*
4,1,15,.00398,.00044,
.003999,.000208,
.004004,-.000025,
.003996,-.000258,
.00398,-.00044,
.00483,-.00129,
.004897,-.001007,
.004947,-.000721,
.004981,-.000432,
.004997,-.000141,
.004997,.000149,
.00498,.00044,
.004946,.000729,
.004895,.001015,
.00483,.00129,
.00398,.00044,
89.996*
4,1,15,.00044,-.00398,
.000208,-.003999,
-.000025,-.004004,
-.000258,-.003996,
-.00044,-.00398,
-.00129,-.00483,
-.001007,-.004897,
-.000721,-.004947,
-.000432,-.004981,
-.000141,-.004997,
.000149,-.004997,
.00044,-.00498,
.000729,-.004946,
.001015,-.004895,
.00129,-.00483,
.00044,-.00398,
89.996*
4,1,15,-.00398,-.00044,
-.003999,-.000208,
-.004004,.000025,
-.003996,.000258,
-.00398,.00044,
-.00483,.00129,
-.004897,.001007,
-.004947,.000721,
-.004981,.000432,
-.004997,.000141,
-.004997,-.000149,
-.00498,-.00044,
-.004946,-.000729,
-.004895,-.001015,
-.00483,-.00129,
-.00398,-.00044,
89.996*
4,1,15,-.00044,.00398,
-.000208,.003999,
.000025,.004004,
.000258,.003996,
.00044,.00398,
.00129,.00483,
.001007,.004897,
.000721,.004947,
.000432,.004981,
.000141,.004997,
-.000149,.004997,
-.00044,.00498,
-.000729,.004946,
-.001015,.004895,
-.00129,.00483,
-.00044,.00398,
89.996*
%
%ADD29MACRO29*%
%ADD28C,.239*%
%ADD10C,.168*%
%AMMACRO27*
4,1,15,.00398,.00044,
.003999,.000208,
.004004,-.000025,
.003996,-.000258,
.00398,-.00044,
.00483,-.00129,
.004897,-.001007,
.004947,-.000721,
.004981,-.000432,
.004997,-.000141,
.004997,.000149,
.00498,.00044,
.004946,.000729,
.004895,.001015,
.00483,.00129,
.00398,.00044,
270.*
4,1,15,.00044,-.00398,
.000208,-.003999,
-.000025,-.004004,
-.000258,-.003996,
-.00044,-.00398,
-.00129,-.00483,
-.001007,-.004897,
-.000721,-.004947,
-.000432,-.004981,
-.000141,-.004997,
.000149,-.004997,
.00044,-.00498,
.000729,-.004946,
.001015,-.004895,
.00129,-.00483,
.00044,-.00398,
270.*
4,1,15,-.00398,-.00044,
-.003999,-.000208,
-.004004,.000025,
-.003996,.000258,
-.00398,.00044,
-.00483,.00129,
-.004897,.001007,
-.004947,.000721,
-.004981,.000432,
-.004997,.000141,
-.004997,-.000149,
-.00498,-.00044,
-.004946,-.000729,
-.004895,-.001015,
-.00483,-.00129,
-.00398,-.00044,
270.*
4,1,15,-.00044,.00398,
-.000208,.003999,
.000025,.004004,
.000258,.003996,
.00044,.00398,
.00129,.00483,
.001007,.004897,
.000721,.004947,
.000432,.004981,
.000141,.004997,
-.000149,.004997,
-.00044,.00498,
-.000729,.004946,
-.001015,.004895,
-.00129,.00483,
-.00044,.00398,
270.*
%
%ADD27MACRO27*%
%AMMACRO26*
4,1,15,.00398,.00044,
.003999,.000208,
.004004,-.000025,
.003996,-.000258,
.00398,-.00044,
.00483,-.00129,
.004897,-.001007,
.004947,-.000721,
.004981,-.000432,
.004997,-.000141,
.004997,.000149,
.00498,.00044,
.004946,.000729,
.004895,.001015,
.00483,.00129,
.00398,.00044,
180.*
4,1,15,.00044,-.00398,
.000208,-.003999,
-.000025,-.004004,
-.000258,-.003996,
-.00044,-.00398,
-.00129,-.00483,
-.001007,-.004897,
-.000721,-.004947,
-.000432,-.004981,
-.000141,-.004997,
.000149,-.004997,
.00044,-.00498,
.000729,-.004946,
.001015,-.004895,
.00129,-.00483,
.00044,-.00398,
180.*
4,1,15,-.00398,-.00044,
-.003999,-.000208,
-.004004,.000025,
-.003996,.000258,
-.00398,.00044,
-.00483,.00129,
-.004897,.001007,
-.004947,.000721,
-.004981,.000432,
-.004997,.000141,
-.004997,-.000149,
-.00498,-.00044,
-.004946,-.000729,
-.004895,-.001015,
-.00483,-.00129,
-.00398,-.00044,
180.*
4,1,15,-.00044,.00398,
-.000208,.003999,
.000025,.004004,
.000258,.003996,
.00044,.00398,
.00129,.00483,
.001007,.004897,
.000721,.004947,
.000432,.004981,
.000141,.004997,
-.000149,.004997,
-.00044,.00498,
-.000729,.004946,
-.001015,.004895,
-.00129,.00483,
-.00044,.00398,
180.*
%
%ADD26MACRO26*%
%ADD31C,.02*%
%ADD32C,.006*%
%ADD36C,.12306*%
%ADD35C,.15006*%
%ADD34C,.13906*%
%ADD33C,.16606*%
G75*
%LPD*%
G75*
G36*
G01X-6000Y-6000D02*
X212693D01*
Y1974504D01*
X-6000D01*
Y-6000D01*
G37*
%LPC*%
G75*
G36*
G01X3937Y3004D02*
G02X3004Y3937I0J933D01*
G01Y1964567D01*
G02X3937Y1965500I933J0D01*
G01X64961D01*
G02X65894Y1964567I0J-933D01*
G01Y1933071D01*
G03X72835Y1926130I6941J0D01*
G01X82250D01*
Y1850689D01*
X84189Y1848750D01*
X86811D01*
X89250Y1851189D01*
Y1926130D01*
X202756D01*
G02X203689Y1925197I0J-933D01*
G01Y43307D01*
G02X202756Y42374I-933J0D01*
G01X72835D01*
G03X65894Y35433I0J-6941D01*
G01Y3937D01*
G02X64961Y3004I-933J0D01*
G01X3937D01*
G37*
G36*
G01X86189Y1850250D02*
X84811D01*
X83750Y1851311D01*
Y1926130D01*
X87750D01*
Y1851811D01*
X86189Y1850250D01*
G37*
%LPD*%
G75*
G54D36*
X80709Y139409D03*
Y309409D03*
X149606Y139409D03*
Y309409D03*
G54D35*
X80709Y119409D03*
Y329409D03*
X149606Y119409D03*
Y329409D03*
G54D34*
X47244Y68110D03*
Y501338D03*
Y761181D03*
Y1207323D03*
Y1467165D03*
Y1900393D03*
G54D33*
X29921Y24803D03*
Y111417D03*
Y458031D03*
Y544646D03*
Y717874D03*
Y804488D03*
X30000Y1164000D03*
X29921Y1250630D03*
Y1423858D03*
Y1510472D03*
Y1857086D03*
Y1943701D03*
G54D30*
X178937Y1328740D03*
X161417Y1747835D03*
Y1823031D03*
G54D19*
X27559Y629921D03*
X17716Y1338583D03*
X27559Y1811023D03*
X179134Y78740D03*
X179133Y570866D03*
X179134Y1161417D03*
G54D15*
X27559Y157480D03*
X179134Y1889764D03*
G54D18*
X26450Y274750D03*
X25500Y321200D03*
X21600Y333800D03*
X23450Y577491D03*
X25148Y570800D03*
X27000Y573800D03*
X13300Y1644300D03*
X10500Y1648800D03*
X13300Y1689600D03*
X19200Y1707000D03*
X25000Y1763800D03*
X70454Y60031D03*
X64500Y53000D03*
X64000Y67553D03*
X81500Y75500D03*
X63500Y63500D03*
X75300Y155300D03*
X49924Y153261D03*
X53400Y191300D03*
X39300Y175500D03*
X43700Y181200D03*
X43400Y174325D03*
X32425Y177900D03*
X52700Y162300D03*
X64400Y183400D03*
X52500Y175200D03*
X70500Y190200D03*
X54400Y217000D03*
X65200Y207850D03*
X57424Y232974D03*
X42720Y233990D03*
X65000Y241500D03*
Y235400D03*
X41100Y231000D03*
X71400Y208150D03*
X69900Y236600D03*
X77900Y229034D03*
X70600Y217600D03*
X74800Y231800D03*
X69400Y226100D03*
X61300Y229400D03*
X38000Y228500D03*
X75300Y211300D03*
X72100Y221700D03*
X49700Y209700D03*
X53500Y199700D03*
X47800Y199200D03*
X64000Y199700D03*
X60300Y275700D03*
X57500Y268500D03*
X68000Y268000D03*
X70600Y250500D03*
X48500Y248600D03*
X42500Y254100D03*
X54000Y275600D03*
X45800Y277800D03*
X43400Y272300D03*
X78000Y429500D03*
X52100Y513100D03*
X46500Y511000D03*
X46000Y516000D03*
X77800Y540300D03*
X33450Y574300D03*
X63400Y581400D03*
X75571Y692496D03*
X53000Y673500D03*
X57684Y697639D03*
X43388Y694286D03*
X44500Y697500D03*
X60900Y670200D03*
X60500Y682540D03*
X76100Y686900D03*
X73000Y728000D03*
X69000Y726800D03*
X49500Y703500D03*
X46500Y705500D03*
X57500Y844500D03*
X72400Y822900D03*
X51200Y827000D03*
X61207Y828350D03*
X49600Y889400D03*
X55700Y880000D03*
X56000Y885500D03*
X64600Y882700D03*
X61600Y885200D03*
X67200Y888800D03*
X54000Y996500D03*
X53500Y1025500D03*
X51000Y1018000D03*
X37500Y1099823D03*
X70500Y1161500D03*
X73163Y1158780D03*
X71100Y1171000D03*
X68800Y1178800D03*
X67700Y1568700D03*
X45300Y1776300D03*
X91500Y88500D03*
X97000Y51500D03*
X115500Y59500D03*
X98500Y73000D03*
X109000Y76500D03*
X115000D03*
X99500Y61000D03*
X89500Y49500D03*
X109500Y62000D03*
X88253Y65500D03*
X93500Y101500D03*
X93900Y111800D03*
X93000Y107000D03*
X91000Y97000D03*
X91500Y92500D03*
X104500Y101000D03*
X112000D03*
X117600Y234900D03*
X122100Y230100D03*
X85676Y231100D03*
X127200Y246000D03*
X122500Y441000D03*
X91300Y528200D03*
X87700Y528000D03*
X132500Y539621D03*
X129000Y597000D03*
X116000Y596900D03*
X113655Y599363D03*
X110400Y550800D03*
X128900Y580500D03*
X122300Y575000D03*
X115300Y551800D03*
X131135Y639554D03*
X86597Y681103D03*
X100200Y663900D03*
X122500Y653650D03*
X117400Y653100D03*
X118127Y663400D03*
X109005Y665890D03*
X114000Y663350D03*
X83850Y678109D03*
X91250Y704700D03*
X86500Y723500D03*
X98900Y822900D03*
X114900Y824100D03*
X106404Y840700D03*
X100300Y841000D03*
X111500Y851600D03*
X101500Y874200D03*
X102300Y863438D03*
X107164Y862285D03*
X113400Y862200D03*
X127200Y1015200D03*
X82094Y1112500D03*
X119500Y1261000D03*
X119000Y1255968D03*
X128700Y1408000D03*
X131174Y1412700D03*
X89000Y1428171D03*
X110000Y1429500D03*
X132000Y1436500D03*
X112750Y1491250D03*
X121000Y1506500D03*
X113000D03*
X117000D03*
X109000D03*
X133000Y1505500D03*
X128999Y1506499D03*
X125000Y1506500D03*
X132300Y1491100D03*
X108500Y1569000D03*
X83000Y1619703D03*
X113200Y1622800D03*
Y1619300D03*
X83050Y1616000D03*
X135500Y441000D03*
X146960Y432400D03*
X165300Y481100D03*
X144000Y509500D03*
X166100Y527900D03*
X162500D03*
X159850Y541800D03*
X182588Y542288D03*
X159250Y590250D03*
X154600Y581500D03*
X160000Y562500D03*
X147900Y588100D03*
X138900Y650100D03*
X174196Y628196D03*
X139200Y653900D03*
X150978Y687775D03*
X142648Y665429D03*
X155200Y679500D03*
X161500Y691700D03*
X150700D03*
X158600Y752600D03*
X153192Y705890D03*
X157800Y898000D03*
X147500Y900500D03*
X143000Y953032D03*
X146500Y953030D03*
X149772Y954121D03*
X152747Y952474D03*
X150500Y976500D03*
X155000Y974500D03*
X135601Y1416200D03*
X139900Y1415100D03*
X134500Y1420000D03*
X158500Y1466500D03*
X151500Y1438500D03*
X157500Y1454800D03*
X142500Y1420500D03*
X142000Y1494800D03*
X147500Y1498000D03*
X153500Y1496500D03*
X135008Y1508245D03*
X143518Y1567520D03*
X177500Y1569500D03*
X141500Y1621600D03*
X141300Y1625000D03*
X169876Y1626303D03*
X173270Y1626517D03*
X191400Y432405D03*
G54D16*
X31299Y230866D03*
Y220866D03*
Y210866D03*
Y338563D03*
Y358563D03*
Y348563D03*
Y903917D03*
Y923917D03*
Y913917D03*
Y1054587D03*
Y1044587D03*
Y1064587D03*
Y1619941D03*
Y1609941D03*
Y1629941D03*
Y1757638D03*
Y1747638D03*
Y1737638D03*
G54D17*
X28050Y256950D03*
X19250Y1663100D03*
X13900Y1706200D03*
X68000Y286000D03*
Y296000D03*
Y320000D03*
Y312000D03*
X76000Y296000D03*
X68000Y304000D03*
X74000Y390000D03*
X66000D03*
X58000D03*
X64000Y446500D03*
X74000Y408000D03*
X66000D03*
Y418000D03*
X74000D03*
X73700Y423000D03*
X66000Y426000D03*
X58000D03*
X74000Y400000D03*
X66000D03*
X58000D03*
Y408000D03*
Y417500D03*
X58100Y431900D03*
X63096Y434540D03*
X68500Y434300D03*
X81000Y410500D03*
X82000Y483600D03*
X46000Y490500D03*
X50100Y493000D03*
X42500D03*
X78200Y481700D03*
X63300Y464400D03*
X64000Y451000D03*
Y455500D03*
Y460000D03*
X62500Y472900D03*
X62600Y468500D03*
X62500Y477000D03*
X78500Y506700D03*
X78200Y501000D03*
X71800Y506900D03*
X71900Y501000D03*
X72100Y521800D03*
X79400D03*
X72000Y514800D03*
X78000D03*
X51700Y522500D03*
X72500Y595900D03*
X56800Y576950D03*
X80900Y668400D03*
X56710Y681069D03*
X40000Y659000D03*
X43281Y674991D03*
X39096Y674917D03*
X41000Y931899D03*
X64000Y980500D03*
X37700Y991600D03*
X31600Y1024300D03*
X39300Y1105800D03*
X67302Y1133490D03*
X78292Y1148041D03*
X64500Y1165700D03*
X53500Y1519000D03*
X72000Y1514000D03*
X58500Y1519000D03*
X57000Y1568500D03*
X57500Y1562000D03*
X59500Y1541000D03*
X54300Y1541200D03*
X80000Y1531600D03*
X73900Y1535900D03*
X54500Y1574000D03*
X71600Y1607700D03*
X50600Y1589300D03*
Y1582800D03*
Y1595300D03*
Y1601300D03*
X55300Y1601100D03*
Y1595100D03*
Y1582600D03*
Y1589100D03*
X68700Y1603900D03*
X55400Y1613300D03*
X58500Y1607700D03*
X59500Y1667000D03*
X70000Y1668000D03*
X76000Y1646000D03*
Y1634000D03*
X75500Y1659500D03*
X54000Y1646500D03*
X64500Y1646000D03*
X55000Y1634000D03*
X64000D03*
X64500Y1658500D03*
X53500Y1659000D03*
X56000Y1695000D03*
Y1704500D03*
Y1712500D03*
X55500Y1723500D03*
X69000Y1684500D03*
X80500D03*
X62500Y1691500D03*
X65000Y1724000D03*
X62500Y1709000D03*
X72500Y1717000D03*
Y1699000D03*
X75500Y1679000D03*
X62500Y1700000D03*
X38800Y1775000D03*
X41600Y1746900D03*
X48400D03*
X64500Y1758500D03*
X55500Y1735500D03*
X65000Y1735000D03*
X79000Y1766500D03*
X65000Y1749000D03*
Y1768000D03*
Y1742500D03*
X71500Y1760000D03*
X72500Y1733000D03*
X60000Y1730000D03*
X42000Y1784400D03*
X81000Y1802000D03*
X73000Y1813000D03*
X64500Y1821500D03*
Y1812000D03*
Y1801500D03*
X65000Y1790000D03*
X72000Y1798000D03*
X39179Y1792306D03*
X75500Y1838500D03*
X63500Y1863000D03*
Y1856000D03*
X64000Y1844500D03*
Y1834000D03*
X73000Y1847000D03*
X72500Y1830000D03*
X102000Y312000D03*
X104000Y304000D03*
X94000D03*
Y312000D03*
Y320000D03*
X114000Y296000D03*
X106000D03*
X96000D03*
X86000D03*
X118000Y396000D03*
Y386000D03*
X89800Y446000D03*
X131000Y447000D03*
X91900Y410500D03*
X84500Y433000D03*
X88500Y426500D03*
X86400Y410500D03*
X118000Y424000D03*
Y404000D03*
X130000Y432000D03*
X118000Y414000D03*
X129000Y485500D03*
X120000D03*
X110800Y482600D03*
X99800Y482000D03*
X110800Y488600D03*
X100000Y488000D03*
Y494000D03*
X110800Y494600D03*
X129000Y493500D03*
X120000D03*
X122500Y450500D03*
Y457500D03*
Y463500D03*
X121500Y475500D03*
X122500Y469500D03*
X117000Y455000D03*
Y460500D03*
Y466000D03*
Y471500D03*
Y449000D03*
X89800Y452900D03*
Y459000D03*
X111500Y473000D03*
X99500D03*
X89800Y464800D03*
X130500Y454000D03*
Y461000D03*
Y468000D03*
Y474500D03*
X120000Y501500D03*
X129000Y517500D03*
X100000Y512000D03*
X110800Y500600D03*
X100000Y500000D03*
X85000Y506400D03*
X84500Y514400D03*
X129000Y501500D03*
Y509500D03*
X110800Y512600D03*
X120000Y517500D03*
X100000Y506000D03*
X110800Y506600D03*
X120000Y509500D03*
Y523500D03*
X129000D03*
X100000Y519100D03*
X90630Y602020D03*
X86443Y662853D03*
X88967Y659749D03*
X84504Y666353D03*
X90674Y663367D03*
X121500Y683500D03*
X119576Y687008D03*
X120702Y690847D03*
X100600Y670600D03*
X112800Y653500D03*
X108200Y655825D03*
X106882Y794201D03*
X107000Y798200D03*
Y802400D03*
X97250Y1023500D03*
X95400Y1064100D03*
X91400D03*
X87000Y1063000D03*
X89000Y1167400D03*
X105500Y1415000D03*
X99600Y1416500D03*
X86900Y1451000D03*
X83500Y1469500D03*
X87200Y1440000D03*
X99800Y1455600D03*
X109500Y1438000D03*
X98500Y1428400D03*
X117000Y1435200D03*
X94000Y1514000D03*
X93000Y1518700D03*
X85200Y1515000D03*
X91300Y1488600D03*
X85000Y1490000D03*
X124500Y1524000D03*
X87900Y1523400D03*
X94000Y1562000D03*
Y1550000D03*
X119000Y1529500D03*
X129000Y1562500D03*
X128000Y1568000D03*
X114000Y1546000D03*
X129000Y1542500D03*
X122000Y1546000D03*
Y1538000D03*
X129000Y1549000D03*
X94000Y1556000D03*
X129000Y1535000D03*
X115900Y1569700D03*
X94000Y1568000D03*
X102000D03*
Y1556000D03*
Y1550000D03*
Y1562000D03*
Y1544000D03*
X114000Y1564000D03*
X121800Y1569929D03*
X122000Y1564000D03*
X114000Y1558000D03*
X122000Y1552000D03*
X114000D03*
X122000Y1558000D03*
X111500Y1537500D03*
X129000Y1555500D03*
X116000Y1576000D03*
X122000D03*
Y1584000D03*
X116000D03*
Y1592000D03*
X122000D03*
X116000Y1600000D03*
X122000Y1612000D03*
X104000Y1605500D03*
X116000Y1612000D03*
X122000Y1600000D03*
X128000Y1606000D03*
X94500Y1605500D03*
X113500D03*
X117500Y1669000D03*
X127500D03*
X86000D03*
X97000D03*
X107000D03*
X127000Y1646000D03*
X118000D03*
X117000Y1633500D03*
X127500Y1633000D03*
Y1659500D03*
X117500D03*
X108000Y1646000D03*
X106000Y1634000D03*
X107000Y1659500D03*
X96000Y1646000D03*
X96500Y1634000D03*
X97000Y1659500D03*
X86000Y1646000D03*
Y1634000D03*
Y1659500D03*
X122000Y1685500D03*
X91000Y1685000D03*
X103000D03*
X112500D03*
X98500Y1717000D03*
Y1696500D03*
X99000Y1707000D03*
X117500Y1679000D03*
X125000D03*
X86000D03*
X97500Y1679500D03*
X107500Y1679000D03*
X109500Y1719500D03*
X110000Y1709500D03*
X109500Y1699000D03*
X119500Y1710110D03*
Y1696610D03*
X86500Y1713610D03*
Y1700110D03*
X119500Y1725110D03*
X111500Y1768500D03*
X108500Y1727000D03*
X117500Y1732000D03*
X119500Y1760000D03*
X97500Y1775500D03*
X86500Y1726000D03*
X87000Y1774110D03*
X119500Y1747110D03*
X110500Y1801000D03*
X88500Y1785000D03*
X97500Y1796000D03*
X98000Y1786000D03*
X86500Y1793110D03*
X108268Y1777300D03*
X107768Y1789110D03*
X120000Y1811500D03*
X119500Y1796500D03*
X114000Y1843500D03*
X97000Y1850500D03*
X99500Y1862500D03*
X106500D03*
X114500D03*
X122500D03*
X120500Y1836500D03*
Y1850500D03*
X108500Y1851610D03*
X85100Y1844500D03*
X132000Y1892000D03*
X124500Y1892403D03*
X116948Y1892000D03*
X142000Y291000D03*
X143400Y318700D03*
X174000Y316000D03*
X164000D03*
X182000Y296000D03*
X172000D03*
X162000D03*
X172000Y310000D03*
X182000D03*
X184000Y303000D03*
X176000Y302000D03*
X166000D03*
X143300Y343400D03*
X151300Y298200D03*
X150000Y386000D03*
X134000Y396000D03*
X150000D03*
X134000Y386000D03*
X161600Y445900D03*
X136000Y447000D03*
X134000Y404500D03*
X174500Y432000D03*
X162000D03*
X145500Y427000D03*
X142000Y432000D03*
X134000Y414000D03*
X150000Y404000D03*
Y414000D03*
X134000Y424000D03*
X150000D03*
X169200Y482800D03*
X144000Y493500D03*
Y486182D03*
X137000Y493000D03*
X136500Y485500D03*
X161900Y451600D03*
X162000Y457600D03*
X161900Y463300D03*
X135500Y454000D03*
Y461000D03*
Y474500D03*
Y468000D03*
X173700Y513900D03*
X144000Y517500D03*
Y501500D03*
X173500Y506000D03*
X173600Y498800D03*
X157100Y500000D03*
X137000Y510000D03*
X137500Y523500D03*
X174900Y523300D03*
X156800Y515400D03*
Y506900D03*
X137000Y501500D03*
X137500Y517500D03*
X152700Y618803D03*
X170349Y619949D03*
X151432Y661741D03*
X148995Y658568D03*
X146800Y1018900D03*
X143900Y1022700D03*
X155000Y1120000D03*
Y1125000D03*
Y1130500D03*
X161500Y1227500D03*
X148300Y1465000D03*
X152500Y1456000D03*
X133799Y1440699D03*
X174000Y1515500D03*
X174500Y1509500D03*
Y1503500D03*
X174000Y1522000D03*
X136000Y1528000D03*
X150000Y1570000D03*
X166898Y1567102D03*
X168500Y1526000D03*
X148000Y1564000D03*
X161300Y1563100D03*
X169500Y1561500D03*
X170000Y1548500D03*
X154000Y1564000D03*
X156000Y1570000D03*
X161400Y1543500D03*
X170000Y1555000D03*
X168500Y1533500D03*
X148000Y1542000D03*
Y1528000D03*
Y1558000D03*
X136000Y1548000D03*
Y1555000D03*
Y1562000D03*
Y1536000D03*
Y1542000D03*
Y1568000D03*
X170000Y1541000D03*
X148000Y1550000D03*
X156000Y1576000D03*
X150000D03*
X156000Y1582000D03*
X156500Y1591000D03*
X150500Y1582000D03*
Y1591000D03*
X172000Y1606000D03*
X182500Y1599400D03*
X146000Y1612000D03*
X148000Y1606000D03*
X182500Y1592000D03*
X164000Y1606000D03*
X156500Y1600000D03*
X156000Y1606000D03*
X150500Y1600000D03*
X138500Y1606000D03*
X182500Y1584500D03*
X176000Y1646000D03*
X166000D03*
X158000D03*
X148000D03*
X176000Y1632000D03*
X178000Y1659500D03*
X167500Y1632500D03*
X170000Y1659500D03*
X149000Y1632500D03*
X159000D03*
X138000Y1634000D03*
X137500Y1659500D03*
X159000D03*
X148500Y1660000D03*
X138000Y1646000D03*
X186500Y498000D03*
X192000Y490000D03*
Y498000D03*
X200300Y498100D03*
X199500Y489400D03*
X188500Y474500D03*
X189900Y467500D03*
Y460500D03*
X190400Y453500D03*
X195000Y467500D03*
X194500Y474500D03*
X195000Y460500D03*
X195500Y453500D03*
X190239Y447449D03*
X195600Y447500D03*
X186500Y513500D03*
Y506000D03*
X192000Y513500D03*
Y506000D03*
X190200Y523400D03*
X201089Y523500D03*
X186500Y519000D03*
X193600Y519100D03*
X200100Y513600D03*
X199800Y506000D03*
X201200Y519200D03*
G54D13*
X15906Y48110D03*
Y58110D03*
Y68110D03*
Y78110D03*
Y481339D03*
Y491339D03*
Y501339D03*
Y511339D03*
Y741181D03*
Y751181D03*
Y761181D03*
Y771181D03*
Y1187323D03*
Y1197323D03*
Y1207323D03*
Y1217323D03*
Y1447165D03*
Y1457165D03*
Y1467165D03*
Y1477165D03*
Y1880394D03*
Y1890394D03*
Y1900394D03*
Y1910394D03*
X128937Y1778819D03*
X118937D03*
X165000Y1390500D03*
Y1380500D03*
Y1370500D03*
X138937Y1778819D03*
G54D25*
X80709Y204409D03*
Y224409D03*
Y244409D03*
Y256929D03*
Y266929D03*
Y276929D03*
Y286929D03*
X110709Y204409D03*
Y214409D03*
Y224409D03*
Y234409D03*
Y244409D03*
X100709Y204409D03*
Y214409D03*
Y224409D03*
Y234409D03*
Y244409D03*
X90709Y214409D03*
Y234409D03*
X110709Y256929D03*
Y266929D03*
X100709Y256929D03*
Y266929D03*
X90709Y256929D03*
Y266929D03*
X110709Y276929D03*
Y286929D03*
X100709Y276929D03*
Y286929D03*
X90709Y276929D03*
Y286929D03*
X179606Y204409D03*
Y214409D03*
Y224409D03*
Y234409D03*
Y244409D03*
X169606Y204409D03*
Y214409D03*
Y224409D03*
Y234409D03*
Y244409D03*
X159606Y214409D03*
Y234409D03*
X149606Y204409D03*
Y224409D03*
Y244409D03*
X179606Y256929D03*
Y266929D03*
X169606Y256929D03*
Y266929D03*
X159606Y256929D03*
Y266929D03*
X149606Y256929D03*
Y266929D03*
X179606Y276929D03*
Y286929D03*
X169606Y276929D03*
Y286929D03*
X159606Y276929D03*
Y286929D03*
X149606Y276929D03*
Y286929D03*
G54D20*
X30000Y782000D03*
X26600Y1570100D03*
X26700Y1579800D03*
X79122Y565700D03*
X79458Y578758D03*
X44000Y782000D03*
X37900Y1570000D03*
X38300Y1579600D03*
X131800Y289700D03*
X130900Y259100D03*
X87595Y581300D03*
X141300Y298100D03*
X181800Y369000D03*
X181100Y364050D03*
X182600Y546900D03*
X141800Y559250D03*
X153500Y574359D03*
X140700Y576600D03*
X188300Y368600D03*
G54D12*
X8594Y6500D03*
X20000Y6000D03*
X17000Y36500D03*
X5594Y87000D03*
Y53500D03*
X29500Y53000D03*
X26000Y87000D03*
X30800Y130300D03*
X4594Y120500D03*
X23500Y124000D03*
X15000Y131500D03*
X14500Y100500D03*
Y112500D03*
X4500Y105500D03*
X5000Y137500D03*
X22500Y190000D03*
X29700Y191400D03*
X5594Y153500D03*
X4594Y187500D03*
X16500Y175000D03*
X15500Y143500D03*
X27000Y182000D03*
X14000Y184000D03*
X4500Y170500D03*
X21500Y241500D03*
X4594Y234000D03*
X24000Y212000D03*
X29000Y200500D03*
X13500Y230500D03*
X13000Y212500D03*
X5000Y221000D03*
X12500Y197500D03*
X4500Y202500D03*
X5094Y278000D03*
X6094Y257000D03*
X13500Y279000D03*
X13000Y244000D03*
X12500Y266500D03*
X5500Y269500D03*
X5000Y247500D03*
X19721Y267203D03*
X5594Y312000D03*
X5304Y342500D03*
X4900Y328000D03*
X13500Y303500D03*
X29500Y343500D03*
X13000Y321000D03*
X13500Y295000D03*
X5500Y295500D03*
X23100Y342400D03*
X6500Y375000D03*
X27000Y371000D03*
X4800Y356200D03*
X23400Y353500D03*
X23700Y363900D03*
X29500Y364500D03*
X27000Y377500D03*
Y384000D03*
Y389500D03*
X4594Y421000D03*
X5304Y444500D03*
Y440500D03*
X5000Y408500D03*
X5304Y434500D03*
X4594Y396500D03*
X29500Y410500D03*
X26500Y440000D03*
X26000Y432500D03*
X23800Y410700D03*
X5094Y469500D03*
X5000Y495000D03*
X4700Y458200D03*
X5000Y486500D03*
X14000Y476000D03*
X28800Y533700D03*
X5304Y548800D03*
Y528900D03*
X5094Y600000D03*
X13510Y597990D03*
X5094Y574500D03*
X29500Y586500D03*
X14000Y614000D03*
X4594Y625000D03*
X18000Y608000D03*
X6000Y612000D03*
Y646000D03*
X26000Y656500D03*
X5594Y688500D03*
X5304Y661000D03*
X14000Y659000D03*
X23000Y677500D03*
X8000Y678000D03*
X31000Y700500D03*
X20000Y696000D03*
X6000Y698000D03*
X28000Y706000D03*
X31000Y747000D03*
X22000Y746000D03*
X27000Y750000D03*
X26000Y732000D03*
X18000Y724000D03*
Y732500D03*
Y712000D03*
X6000Y706500D03*
Y722000D03*
Y730500D03*
X4594Y749000D03*
Y714000D03*
X5594Y778000D03*
X6500Y799000D03*
X9500Y804000D03*
X24000Y756000D03*
X16100Y794600D03*
X5594Y844500D03*
X6094Y819500D03*
X30500D03*
X10000Y811500D03*
X24000Y846000D03*
X24500Y853500D03*
X16000Y828000D03*
Y814000D03*
Y856000D03*
Y842000D03*
X4500Y833500D03*
X26053Y828247D03*
X5094Y897500D03*
X5594Y869000D03*
X16000Y906000D03*
X18000Y884000D03*
Y870000D03*
X4500Y857500D03*
X5000Y883500D03*
X18500Y896500D03*
X23053Y861247D03*
X5304Y926000D03*
X4594Y954000D03*
X18000Y934000D03*
Y920000D03*
X16000Y948000D03*
X4500Y913000D03*
Y941500D03*
X26053Y938247D03*
X5594Y984500D03*
X28000Y992000D03*
X16000Y962000D03*
Y990000D03*
Y976000D03*
Y1000000D03*
X4500Y970000D03*
Y997000D03*
X25053Y971247D03*
X4594Y1041500D03*
Y1013500D03*
X6000Y1058000D03*
X26000Y1010000D03*
X16000Y1014000D03*
Y1046000D03*
Y1032000D03*
X14000Y1060000D03*
X4500Y1029500D03*
X27553Y1029247D03*
X5094Y1074500D03*
X28000Y1072000D03*
X14000Y1074000D03*
Y1100000D03*
Y1086000D03*
X16000Y1110000D03*
X6000Y1096000D03*
X26100Y1088600D03*
X27218Y1097000D03*
X16000Y1124000D03*
Y1148000D03*
Y1134000D03*
Y1162000D03*
X6000Y1138000D03*
Y1118000D03*
Y1152000D03*
X26600Y1132400D03*
X24553Y1153247D03*
X5304Y1208000D03*
X4594Y1169500D03*
X24000Y1180000D03*
X16000Y1176000D03*
X8500Y1237000D03*
X30000Y1240000D03*
X16000Y1262000D03*
Y1244000D03*
X6000Y1252000D03*
X22000Y1232000D03*
X6500Y1302000D03*
X5094Y1268500D03*
X17700Y1283000D03*
X12000Y1274000D03*
Y1294000D03*
X28000Y1266000D03*
Y1286000D03*
Y1300000D03*
X19800Y1315400D03*
X13500Y1365000D03*
X6000Y1318000D03*
X28000Y1320000D03*
X5094Y1354500D03*
X30800Y1403900D03*
X5304Y1409400D03*
X4594Y1382000D03*
X7500Y1376500D03*
X8000Y1368000D03*
X4800Y1460700D03*
X4594Y1435500D03*
X5304Y1504100D03*
X4600Y1484800D03*
X29500Y1495800D03*
X5304Y1540500D03*
Y1522100D03*
X26700Y1529800D03*
X26900Y1547900D03*
Y1559100D03*
X4594Y1607500D03*
X5304Y1576200D03*
X28000Y1596800D03*
X7500Y1640200D03*
X5304Y1659000D03*
X4594Y1632000D03*
X29000Y1671000D03*
X5304Y1723500D03*
X4900Y1708000D03*
X4594Y1691000D03*
X4700Y1676100D03*
X19542Y1710518D03*
X29100Y1721550D03*
X30000Y1731000D03*
X4594Y1775000D03*
Y1751000D03*
X12600Y1753800D03*
X13100Y1742600D03*
Y1728900D03*
X12900Y1765200D03*
X4594Y1826500D03*
X5900Y1814100D03*
X4594Y1799500D03*
X12600Y1792800D03*
X12500Y1782500D03*
X26750Y1791100D03*
X4594Y1878500D03*
X12800Y1863700D03*
X5000Y1864100D03*
X18600Y1871400D03*
X4594Y1850000D03*
X24200Y1836700D03*
X15000Y1854900D03*
X14500Y1842000D03*
X27500Y1874500D03*
X24800Y1926500D03*
X5094Y1921000D03*
X4594Y1902000D03*
X24500Y1884000D03*
X27400Y1899400D03*
X13100Y1933900D03*
X16100Y1950700D03*
X5094Y1944500D03*
X15500Y1942500D03*
X4500Y1936000D03*
X6500Y1962000D03*
X25000Y1962500D03*
X12500Y1959000D03*
X63594Y7000D03*
Y25500D03*
X40594Y6000D03*
X49000Y18500D03*
X43000Y27000D03*
X64000Y17000D03*
X53000Y5000D03*
X31500Y5500D03*
X51500Y53000D03*
X74000Y60500D03*
X79000Y65500D03*
X75000Y67500D03*
X74000Y45000D03*
X64500Y40000D03*
X32000D03*
X63098Y119103D03*
X52000Y115600D03*
X51700Y131700D03*
X34400Y95300D03*
X59600Y125800D03*
X71000Y131859D03*
X37000Y124000D03*
X53000Y171500D03*
X62598Y141103D03*
X51900Y145700D03*
X65000Y166300D03*
X60350Y151950D03*
X69000Y153000D03*
X73500Y146000D03*
X39300Y181100D03*
X60800Y147700D03*
X63500Y179300D03*
X54200Y220700D03*
Y207850D03*
X51700Y234800D03*
X58936Y256289D03*
X36000Y260386D03*
X42500Y260200D03*
X34200Y284800D03*
X52500Y248500D03*
X32600Y290500D03*
X50800Y266400D03*
X32675Y299500D03*
X34000Y448000D03*
X33200Y468900D03*
X51000Y529500D03*
X71445Y532192D03*
X72397Y528297D03*
X74942Y530983D03*
X49700Y568900D03*
X34100Y566600D03*
X36000Y554000D03*
X66000Y550500D03*
X65000Y561500D03*
X78400Y583700D03*
X70350Y558850D03*
X54600Y573400D03*
X71800Y701300D03*
X64000Y666600D03*
X66200Y653500D03*
X82000Y652000D03*
X52500Y682500D03*
X32000Y666000D03*
X53000Y695100D03*
X39800Y681400D03*
X50000Y712500D03*
Y749000D03*
X40000Y746500D03*
X36000Y730000D03*
X46000Y726000D03*
X71500Y735500D03*
X73500Y732000D03*
X42000Y802000D03*
Y788000D03*
X47600Y796800D03*
X81500Y837500D03*
X82000Y806500D03*
X48000Y816000D03*
X38000Y834000D03*
Y820000D03*
X46000Y848000D03*
Y834000D03*
X32000Y844000D03*
X78300Y832600D03*
X77600Y849100D03*
X48100Y853400D03*
X45600Y827500D03*
X59500Y881600D03*
X57500Y890300D03*
X37500Y907500D03*
X77000Y871500D03*
X79000Y857000D03*
X62500Y862000D03*
X61500Y876500D03*
X78000Y878500D03*
X32000Y858000D03*
Y886000D03*
Y872000D03*
X77500Y907000D03*
X78300Y893900D03*
X77000Y863000D03*
X47000Y877600D03*
X40900Y901500D03*
X37500Y912000D03*
X34000Y944000D03*
Y934500D03*
X33500Y953000D03*
X61500Y938500D03*
X81500Y940000D03*
X75500Y936500D03*
X69500Y939000D03*
X55500Y955500D03*
X56500Y940000D03*
X62500Y924500D03*
X70000Y914500D03*
Y925500D03*
X76500Y927000D03*
X77500Y917000D03*
X54300Y915500D03*
X70800Y990500D03*
X33500Y962500D03*
X34000Y984000D03*
Y974500D03*
Y1008000D03*
X55500Y968000D03*
X76400Y999100D03*
X57500Y987800D03*
Y984300D03*
X53800Y1006200D03*
X33600Y1029900D03*
X34000Y1017500D03*
X56000Y1021500D03*
X54500Y1035500D03*
X34000Y1102000D03*
Y1072000D03*
X33550Y1080100D03*
X64500Y1099000D03*
X37500Y1118900D03*
X34000Y1144000D03*
X40000Y1136000D03*
Y1156000D03*
X32000Y1114000D03*
X58000Y1206000D03*
X60000Y1194000D03*
X61000Y1173000D03*
X54000Y1184000D03*
X44000Y1194000D03*
X42000Y1242000D03*
X50000Y1244000D03*
X58000Y1250000D03*
X46000Y1218000D03*
X31500Y1222000D03*
X58000D03*
X39500Y1231000D03*
X51800Y1231600D03*
X50100Y1261500D03*
X42000Y1266000D03*
Y1290000D03*
X34000Y1312000D03*
X40000Y1278000D03*
Y1298000D03*
X44000Y1306000D03*
X58000Y1312000D03*
Y1292000D03*
Y1272000D03*
X52000Y1296300D03*
X61000Y1363500D03*
X38000Y1334000D03*
X50000Y1318000D03*
X44000Y1326000D03*
Y1340000D03*
X54000Y1330000D03*
X72000Y1360000D03*
X39400Y1381300D03*
X31500Y1397500D03*
X81500Y1382000D03*
Y1416500D03*
Y1404000D03*
X52500Y1368500D03*
X71800Y1373900D03*
X70500Y1378500D03*
X69400Y1402900D03*
X39500Y1407900D03*
X55600Y1381700D03*
X48900Y1390500D03*
X60900D03*
X56700Y1400100D03*
X68800Y1417800D03*
X58800Y1412400D03*
X49000Y1413300D03*
X72900Y1393600D03*
X74900Y1408800D03*
X44500Y1380500D03*
X45500Y1400000D03*
X32000Y1391500D03*
X61500Y1380000D03*
X70400Y1444500D03*
X79000Y1436400D03*
X76200Y1430700D03*
X60600Y1423600D03*
X75600Y1420300D03*
X66500Y1433500D03*
X53100Y1430700D03*
X42600Y1444200D03*
X34000Y1465900D03*
X49100Y1448400D03*
X68500Y1454600D03*
X74500Y1461800D03*
X72300Y1469800D03*
X59000Y1444500D03*
X77000Y1449000D03*
X58100Y1459300D03*
X45000Y1428000D03*
X63000Y1482300D03*
X42700Y1500000D03*
X72700Y1480500D03*
X46500Y1484900D03*
X64100Y1495400D03*
X73000Y1491200D03*
X43300Y1518500D03*
X49500Y1505000D03*
X59000Y1472000D03*
X34000Y1477600D03*
X80000Y1472000D03*
X46600Y1541100D03*
X45300Y1563600D03*
X36400Y1523400D03*
X45900Y1532800D03*
X45400Y1523800D03*
X38800Y1541700D03*
X38300Y1561800D03*
X44400Y1592100D03*
X33100Y1587400D03*
X43500Y1620700D03*
X42700Y1606000D03*
X38400Y1596700D03*
X42500Y1673000D03*
X35500Y1670500D03*
X43200Y1634800D03*
X43600Y1668300D03*
X43300Y1646600D03*
X31400Y1648200D03*
X42500Y1699500D03*
X45500Y1690000D03*
X41500Y1692000D03*
X44500Y1678000D03*
X40300Y1703900D03*
X44100Y1685200D03*
X44600Y1724400D03*
X44900Y1706800D03*
X34000Y1691500D03*
X52500Y1756000D03*
X53000Y1750500D03*
X36700Y1764700D03*
X56500Y1769300D03*
X44900Y1740300D03*
X44400Y1821400D03*
X39700Y1869700D03*
X46700Y1857700D03*
X46500Y1850200D03*
X44500Y1833500D03*
X39700Y1846600D03*
X45500Y1865000D03*
X31500Y1878500D03*
X36000Y1835500D03*
X62000Y1877000D03*
X54500Y1889500D03*
X63500Y1928000D03*
X61500Y1922500D03*
X46000Y1923000D03*
X57900Y1899800D03*
X65300Y1886600D03*
X55900Y1881500D03*
X38700Y1893800D03*
X41500Y1889500D03*
X60300Y1892300D03*
X47000Y1886200D03*
X79900Y1923000D03*
X54000Y1928500D03*
X35300Y1925300D03*
X36500Y1900500D03*
X63500Y1963000D03*
X63594Y1935500D03*
X61600Y1954700D03*
X34500Y1963200D03*
X41100Y1957500D03*
X55300Y1959100D03*
X45100Y1933400D03*
X35000Y1933500D03*
X43500Y1945000D03*
X49053Y1951747D03*
X128500Y89000D03*
X118000Y54500D03*
X124000Y74500D03*
X105000Y55000D03*
X85000Y45000D03*
X105000D03*
X95000D03*
X115000D03*
X125000D03*
X84500Y56500D03*
X92500Y73000D03*
X127700Y119200D03*
X128700Y104200D03*
X131000Y138100D03*
X118000Y124500D03*
X119000Y109500D03*
X95000Y125000D03*
X105000D03*
X95000Y134000D03*
X86000Y152000D03*
X129000Y160100D03*
X131000Y150100D03*
X118000Y154500D03*
Y142500D03*
X95000Y143000D03*
X105000D03*
X95000Y155000D03*
X105000D03*
X105500Y390000D03*
Y406500D03*
X101500D03*
X107000Y426500D03*
X98000D03*
X102500D03*
X110500Y406500D03*
X108100Y477650D03*
X117000Y530000D03*
X108900Y541300D03*
X102700Y541000D03*
X124200Y568400D03*
X119800Y568300D03*
X88000Y586500D03*
X101000Y583000D03*
X96000Y588000D03*
X89000Y595000D03*
X87000Y591000D03*
X103100Y587600D03*
X121000Y581500D03*
X124900Y582000D03*
X91300Y577000D03*
X92200Y553800D03*
X106300Y553200D03*
X84200Y643865D03*
X87000Y648000D03*
X87310Y676796D03*
X130000Y700500D03*
X122500D03*
X114500D03*
X105500Y702500D03*
X93000Y698500D03*
X88500Y700000D03*
X98000Y698500D03*
X129800Y696800D03*
X98000Y674327D03*
X102913Y673973D03*
X107113Y674001D03*
X108500Y695500D03*
X103500D03*
X99001Y694866D03*
X125000Y734000D03*
X116500Y752000D03*
X125000Y751000D03*
X125500Y741500D03*
X130000Y736500D03*
Y753000D03*
Y746000D03*
X119500Y746500D03*
Y739500D03*
X113500Y729000D03*
Y736000D03*
Y747000D03*
Y721000D03*
X106000Y709000D03*
X98000Y703000D03*
Y708000D03*
X120500Y732500D03*
X120000Y717500D03*
X115000Y704500D03*
X123000Y800000D03*
X122500Y792500D03*
X114000Y800000D03*
X113500Y792500D03*
X130000Y800000D03*
X129500Y792500D03*
X121500Y783500D03*
X121000Y776000D03*
X129500Y782000D03*
X129000Y774500D03*
X130000Y764000D03*
X119500Y757500D03*
X113500Y756000D03*
X125000Y758500D03*
X115200Y784200D03*
X115000Y773200D03*
X121000Y767900D03*
X95500Y841500D03*
X82500Y814000D03*
X123500Y842500D03*
Y816000D03*
X123000Y808500D03*
X115000Y813000D03*
X114500Y805500D03*
X129200Y830400D03*
X129800Y813500D03*
X124500Y825100D03*
X90500Y831500D03*
X87000Y839500D03*
X118700Y840700D03*
X85500Y903000D03*
X116053Y903247D03*
X127000Y903000D03*
X90000Y893000D03*
X102500Y893500D03*
X117500Y893000D03*
X125000Y868500D03*
X124500Y858000D03*
X107000Y903000D03*
X124500Y876500D03*
X126000Y892500D03*
X96053Y903247D03*
X83400Y878600D03*
X125500Y944000D03*
X105000Y958000D03*
X86500Y932000D03*
X96500Y916500D03*
X107000Y918000D03*
X115000Y920000D03*
X125500D03*
X126000Y930000D03*
X115500D03*
X99000Y953000D03*
X88500Y940500D03*
X120000Y916000D03*
X124000Y909000D03*
X113500Y909500D03*
X103500D03*
X94000Y910500D03*
X85500Y915000D03*
X126000Y954000D03*
X110000Y949500D03*
X117529Y948844D03*
X93000Y925500D03*
X125400Y983600D03*
Y992000D03*
X125000Y967000D03*
X130500Y966000D03*
X124000Y971500D03*
X117000Y1008500D03*
X105500Y996000D03*
X95500Y999000D03*
X87000Y997500D03*
X106500Y1008500D03*
X119000Y975000D03*
X108500Y964000D03*
Y971000D03*
X97300Y990800D03*
X114800Y1005000D03*
X124618Y959244D03*
X83500Y976300D03*
Y972800D03*
X83000Y979800D03*
X94000Y971800D03*
X110500Y1041500D03*
X111500Y1030000D03*
Y1020000D03*
X104000Y1014000D03*
X110500Y1051000D03*
X103500Y1042000D03*
Y1028500D03*
X116500Y1049000D03*
Y1035500D03*
X117500Y1023500D03*
X104000Y1049500D03*
X120000Y1108000D03*
Y1102000D03*
X115000Y1108500D03*
X110500Y1064500D03*
Y1112000D03*
X103500Y1073500D03*
X104500Y1095000D03*
X116500Y1076000D03*
X109000Y1083500D03*
X116500Y1062500D03*
X104000D03*
X118500Y1166000D03*
X105000Y1196000D03*
X119300Y1191400D03*
X119500Y1177500D03*
Y1205500D03*
X104500Y1208000D03*
X105000Y1181000D03*
X94000Y1189000D03*
X91500Y1200000D03*
X99000Y1265500D03*
X117500Y1251000D03*
X112000Y1250500D03*
Y1244500D03*
X119300Y1245400D03*
Y1219400D03*
X119500Y1231500D03*
X104500Y1219500D03*
X92000Y1254000D03*
X103500Y1229000D03*
X92000Y1241500D03*
X103000Y1244900D03*
X92000Y1214500D03*
X91500Y1229000D03*
X119000Y1269000D03*
X99500Y1310000D03*
Y1294000D03*
X98000Y1282000D03*
X123800Y1283900D03*
X124000Y1270000D03*
X113800Y1287900D03*
X114000Y1274000D03*
X123800Y1311900D03*
X124000Y1298000D03*
X92000Y1295500D03*
X91500Y1314500D03*
X114500Y1296500D03*
X97800Y1327900D03*
X123800Y1337900D03*
X124000Y1324000D03*
X113800Y1331900D03*
X114000Y1318000D03*
X115800Y1363900D03*
X116000Y1350000D03*
X123800Y1365900D03*
X124000Y1352000D03*
X83800Y1365900D03*
X84000Y1352000D03*
X93800Y1353900D03*
X94000Y1340000D03*
Y1366000D03*
X90800Y1331200D03*
X100500Y1384500D03*
Y1389000D03*
X124000Y1376500D03*
X125000Y1398500D03*
X100860Y1402260D03*
X111000Y1394000D03*
X114000Y1376000D03*
X114500Y1370500D03*
X83800Y1391900D03*
X93800Y1379900D03*
Y1393200D03*
X93600Y1407100D03*
X97500Y1412000D03*
X89700Y1409700D03*
X110000Y1418000D03*
X125100Y1402500D03*
X126600Y1461500D03*
X132200Y1424800D03*
X94000Y1427800D03*
X87200Y1431900D03*
X87700Y1446500D03*
X87300Y1436000D03*
X95500Y1468000D03*
X113024Y1452079D03*
X117122Y1448001D03*
X117195Y1456070D03*
X121338Y1452021D03*
X117024Y1452000D03*
X83200Y1455500D03*
X97000Y1503100D03*
X93500Y1482700D03*
X99170Y1485790D03*
X103700Y1470300D03*
X85700Y1852300D03*
X118000Y1922000D03*
X91100Y1922800D03*
X128900Y1923300D03*
X104600Y1923400D03*
X149500Y52000D03*
X184000Y55500D03*
X174000D03*
X164000D03*
X154000Y75500D03*
X135000Y50000D03*
Y70000D03*
Y45000D03*
X145000D03*
X155000D03*
X165000D03*
X175000D03*
X137200Y123600D03*
X180500Y112000D03*
X167000Y130500D03*
X176000Y131000D03*
X167000Y93000D03*
X153000Y90500D03*
X171500Y105500D03*
X170500Y120500D03*
X146500Y131859D03*
X154000Y105500D03*
X147600Y150900D03*
X165300Y145200D03*
X137900Y171400D03*
X174500Y143500D03*
X173500Y151500D03*
X138800Y162100D03*
X142000Y478500D03*
X147000Y529900D03*
X144600Y533800D03*
X180500Y595000D03*
X171600Y595400D03*
X133500Y575500D03*
X145800Y594400D03*
X137000Y589900D03*
X133500Y582000D03*
X134600Y586700D03*
X147500Y551500D03*
X156300Y552100D03*
X142500Y550000D03*
X135000Y561500D03*
X150500Y596000D03*
X142100Y581400D03*
X145500Y604000D03*
X175800Y617635D03*
X164950Y615700D03*
X180500Y627771D03*
X165600Y630269D03*
X165433Y692372D03*
X134600Y665600D03*
X161000Y674000D03*
X157500Y664500D03*
X176000Y679000D03*
Y665500D03*
X149000Y677000D03*
X167300Y653800D03*
X162300Y659100D03*
X183500Y698000D03*
X165500Y677500D03*
X159700Y652000D03*
X166000Y751500D03*
X170000Y745500D03*
X161600Y739800D03*
X161500Y747500D03*
X146000Y726000D03*
X165900Y717300D03*
X181000Y729000D03*
Y715500D03*
X182500Y745000D03*
X147000Y703000D03*
X146000Y738000D03*
X181500Y738500D03*
X169100Y722100D03*
X175100Y710000D03*
X169000Y795500D03*
X178000Y797500D03*
X146000Y755000D03*
Y765500D03*
Y796500D03*
Y782500D03*
X175000Y786500D03*
X166000Y760000D03*
X166500Y775500D03*
X161500Y759000D03*
Y768000D03*
Y778000D03*
X182500Y758500D03*
X173500Y777500D03*
Y764000D03*
X172000Y757500D03*
X181700Y768400D03*
X165000Y786000D03*
X171500Y819500D03*
X163500Y805500D03*
X177500Y812000D03*
X146500D03*
X146000Y824000D03*
X177500Y826500D03*
X180000Y856000D03*
X162000Y817500D03*
X174000Y834500D03*
X168000Y830000D03*
X140500Y846500D03*
X134500Y840500D03*
X145500Y885000D03*
X180000Y872500D03*
X179500Y884000D03*
X179900Y900900D03*
X137500Y903000D03*
X146000Y893000D03*
X135000D03*
X134500Y885500D03*
X137500Y876500D03*
X145500Y856500D03*
X157500Y858000D03*
X156300Y877200D03*
X156500Y889000D03*
X153500Y941000D03*
X141000Y938500D03*
X135000Y918000D03*
X135500Y927500D03*
X144000Y919500D03*
Y929000D03*
X179900Y925700D03*
X179800Y941400D03*
X180000Y912500D03*
X143000Y910500D03*
X135500Y909000D03*
X154700Y909700D03*
X154500Y926500D03*
X182000Y950500D03*
X133500Y938000D03*
X163200Y985200D03*
X163100Y978600D03*
X149800Y1008700D03*
X134000Y990500D03*
X179000Y1005000D03*
X180000Y960400D03*
X180500Y973200D03*
X136500Y967000D03*
X184000Y987500D03*
X135000Y975500D03*
X155500Y1030000D03*
X153500Y1033500D03*
X151500Y1030500D03*
X174000Y1012400D03*
X166300Y1021300D03*
X182500Y1041500D03*
X163000Y1042500D03*
X182000Y1029500D03*
Y1016000D03*
X171000Y1046000D03*
Y1032500D03*
X175000Y1059000D03*
X160500Y1053500D03*
X181000Y1051000D03*
X164700Y1033600D03*
X176000Y1018500D03*
X183500Y1065500D03*
X171000Y1068000D03*
X166000Y1080000D03*
X173000Y1082000D03*
X165000Y1097000D03*
X181000Y1098500D03*
X159500Y1062000D03*
X175000Y1072500D03*
X160500Y1067000D03*
X170000Y1103000D03*
Y1089500D03*
X157000Y1101500D03*
X159500Y1087500D03*
X181000Y1079500D03*
X154600Y1111000D03*
X158500Y1075800D03*
X158595Y1110789D03*
X181000Y1112500D03*
X177102Y1129800D03*
X171502Y1129547D03*
X147500Y1165500D03*
Y1186000D03*
X178644Y1202519D03*
X163344Y1181200D03*
X147500Y1221500D03*
X146500Y1241500D03*
X147000Y1265500D03*
X183500Y1241500D03*
X165000Y1264500D03*
X147500Y1288000D03*
Y1311000D03*
X164500Y1299500D03*
X147500Y1332000D03*
X147000Y1348000D03*
X147500Y1366500D03*
X147000Y1377000D03*
X146500Y1417619D03*
Y1397100D03*
X155900D03*
X137000Y1429200D03*
X173375Y1432500D03*
X149686Y1460007D03*
X133500Y1467100D03*
X169000Y1426750D03*
X141500Y1673000D03*
X139000Y1696500D03*
Y1712500D03*
X181500Y1716500D03*
X158500D03*
X167500Y1716000D03*
X182000Y1704000D03*
X168500Y1705000D03*
X158500D03*
X163000Y1697000D03*
X174268Y1697110D03*
X152000D03*
Y1710610D03*
Y1725610D03*
X138500Y1727500D03*
X182000Y1726000D03*
X183600Y1765100D03*
X162500Y1773000D03*
X152500Y1771110D03*
X173268Y1776000D03*
X139000Y1800500D03*
X138000Y1824000D03*
X169000Y1781500D03*
X156500Y1782000D03*
X155500Y1798500D03*
X166500Y1798000D03*
X179000Y1798500D03*
X162000Y1790000D03*
X172768Y1790110D03*
X152000D03*
X139000Y1851000D03*
X138500Y1839500D03*
X161500Y1852500D03*
X183100Y1838300D03*
X160500Y1877500D03*
X173000Y1852610D03*
X151500Y1851110D03*
X170000Y1920500D03*
X161000Y1901500D03*
X162100Y1912000D03*
X151900Y1891400D03*
X146300Y1913700D03*
X142400Y1923800D03*
X176700Y1923900D03*
X177700Y1912800D03*
X152500Y1883100D03*
X157900Y1923100D03*
X133500Y1906500D03*
X194000Y55500D03*
X185000Y45000D03*
X195000D03*
X200000Y55000D03*
Y65000D03*
Y75000D03*
Y85000D03*
X187500Y130500D03*
X190500Y105000D03*
X189500Y120000D03*
X200000Y100000D03*
Y120000D03*
Y140000D03*
X191900Y167700D03*
X191700Y186500D03*
X186000Y143000D03*
X201089Y181700D03*
X197500Y151500D03*
X185500D03*
X201500Y165000D03*
X191800Y234900D03*
Y221100D03*
X191600Y206900D03*
X201500Y208000D03*
X201000Y222500D03*
X200500Y235000D03*
Y195900D03*
X191900Y244600D03*
X202000Y274000D03*
Y254000D03*
X201089Y282600D03*
X202000Y264000D03*
X187500Y338000D03*
X202000Y340000D03*
Y328000D03*
Y295000D03*
X201089Y305500D03*
Y315500D03*
X184500Y325500D03*
X201500Y378000D03*
X202000Y366500D03*
Y353000D03*
X192600Y392600D03*
X201089Y388400D03*
X201500Y397500D03*
X200500Y437500D03*
X201000Y430500D03*
X201089Y407000D03*
X200000Y420500D03*
X192471Y397355D03*
X192400Y401900D03*
X186600Y425750D03*
X192300Y410950D03*
X192409Y417655D03*
X201500Y544500D03*
X201089Y529500D03*
X192400Y529400D03*
X191900Y538200D03*
X201500Y535000D03*
X192000Y543500D03*
X202000Y578000D03*
Y586000D03*
Y595000D03*
X193700D03*
X194400Y586000D03*
X201500Y552500D03*
X201089Y558000D03*
X201500Y564000D03*
X201089Y570600D03*
X190500Y550500D03*
X202000Y607500D03*
X196500Y641500D03*
X192600Y633000D03*
X201500Y621500D03*
X202000Y650500D03*
X194000Y628500D03*
Y615000D03*
X192500Y645000D03*
X202210Y638500D03*
X195000Y670000D03*
X185000Y673500D03*
X188100Y689100D03*
X197500Y685000D03*
X202000Y676500D03*
X192500Y658500D03*
X191500Y692500D03*
X193100Y679000D03*
X184700Y663900D03*
X201500Y691500D03*
X202500Y666000D03*
X196000Y718500D03*
X184500Y708500D03*
X197000Y704000D03*
X195500Y739000D03*
X197500Y753000D03*
X202000Y710000D03*
Y740500D03*
X191500Y724000D03*
Y710500D03*
Y746500D03*
X201500Y726500D03*
X196000Y789500D03*
X196500Y797000D03*
X187900Y785300D03*
X202000Y765000D03*
Y786000D03*
X191500Y760000D03*
X194500Y782500D03*
Y769000D03*
X202500Y755500D03*
X201500Y777000D03*
X201389Y797000D03*
X196800Y828500D03*
X197000Y815000D03*
X190000Y823500D03*
X190500Y831000D03*
X202000Y807500D03*
X201500Y835500D03*
X192500Y853000D03*
Y839500D03*
X185000Y843500D03*
X202500Y822000D03*
Y846500D03*
X202000Y859500D03*
Y890000D03*
X184500Y879000D03*
Y865500D03*
X192000Y879000D03*
Y865500D03*
X194000Y907000D03*
Y893500D03*
X187000Y891000D03*
X202210Y903500D03*
X202000Y875000D03*
X202500Y945500D03*
X202000Y918000D03*
X192000Y934500D03*
Y921000D03*
Y948500D03*
X185000Y917500D03*
X201500Y931500D03*
X202500Y1006000D03*
Y977500D03*
X192000Y962000D03*
X192500Y985500D03*
Y972000D03*
X195500Y1001000D03*
X202500Y962000D03*
X201500Y991000D03*
X190000Y1052000D03*
X202000Y1037000D03*
X195500Y1014500D03*
X193500Y1042500D03*
Y1029000D03*
X202000Y1052000D03*
X201500Y1019000D03*
X195000Y1086500D03*
X194500Y1100500D03*
X201389Y1067000D03*
X195000Y1074500D03*
Y1061000D03*
X201000Y1106500D03*
Y1093000D03*
X187500Y1103500D03*
Y1090000D03*
X201500Y1082500D03*
X195000Y1112000D03*
X201500Y1147000D03*
X202000Y1212000D03*
X202500Y1179000D03*
X202000Y1246000D03*
X191800Y1280900D03*
X201500Y1310000D03*
X202500Y1280000D03*
X201500Y1359500D03*
X200700Y1348500D03*
X201700Y1388300D03*
X201500Y1413000D03*
X202400Y1444000D03*
X201389Y1425500D03*
X202210Y1462000D03*
X194500Y1546000D03*
X193000Y1556500D03*
X197000Y1551500D03*
X195500Y1530500D03*
X193000Y1562500D03*
X189400Y1544100D03*
X187900Y1566600D03*
X201500Y1569000D03*
X202000Y1537500D03*
X202210Y1554000D03*
X187500Y1559500D03*
X189500Y1577000D03*
X198500Y1584000D03*
X192000Y1586000D03*
X197500Y1593000D03*
X191500Y1595000D03*
X199000Y1619500D03*
X190000Y1622000D03*
X196500Y1606500D03*
X198000Y1632500D03*
X191500Y1631000D03*
X198000Y1647500D03*
X196500Y1656000D03*
X191700Y1652700D03*
X192500Y1648000D03*
X192650Y1641500D03*
X197000Y1713000D03*
Y1691500D03*
X184500Y1696500D03*
X197500Y1776500D03*
Y1754000D03*
X197000Y1735500D03*
X185000Y1738500D03*
X198000Y1818500D03*
X196500Y1800500D03*
X185500Y1804500D03*
X186000Y1790000D03*
X197500Y1860000D03*
X197000Y1838500D03*
X194400Y1876700D03*
X185000Y1852500D03*
X200500Y1876500D03*
X201500Y1900500D03*
X190500Y1924000D03*
X201000Y1923000D03*
X195500Y1905000D03*
X196500Y1882000D03*
X184500Y1920500D03*
X201200Y1890500D03*
X201100Y1908800D03*
G54D14*
X15906Y88110D03*
Y521339D03*
Y781181D03*
Y1227323D03*
Y1487165D03*
Y1920394D03*
G54D24*
X80709Y161889D03*
Y171889D03*
Y181889D03*
Y191889D03*
Y214409D03*
Y234409D03*
X110709Y161889D03*
Y171889D03*
X100709Y161889D03*
Y171889D03*
X90709Y161889D03*
Y171889D03*
X110709Y181889D03*
Y191889D03*
X100709Y181889D03*
Y191889D03*
X90709Y181889D03*
Y191889D03*
Y204409D03*
Y224409D03*
Y244409D03*
X179606Y161889D03*
Y171889D03*
X169606Y161889D03*
Y171889D03*
X159606Y161889D03*
Y171889D03*
X149606Y161889D03*
Y171889D03*
X179606Y181889D03*
Y191889D03*
X169606Y181889D03*
Y191889D03*
X159606Y181889D03*
Y191889D03*
X149606Y181889D03*
Y191889D03*
X159606Y204409D03*
Y224409D03*
Y244409D03*
X149606Y214409D03*
Y234409D03*
G54D11*
X29921Y24803D03*
Y111417D03*
Y458031D03*
Y544646D03*
Y717874D03*
Y804488D03*
X30000Y1164000D03*
X29921Y1250630D03*
Y1423858D03*
Y1510472D03*
Y1857086D03*
Y1943701D03*
G54D21*
X47244Y68110D03*
Y501338D03*
Y761181D03*
Y1207323D03*
Y1467165D03*
Y1900393D03*
G54D22*
X80709Y119409D03*
Y329409D03*
X149606Y119409D03*
Y329409D03*
G54D23*
X80709Y139409D03*
Y309409D03*
X149606Y139409D03*
Y309409D03*
G54D29*
X111500Y390000D03*
X101300Y390100D03*
X111200Y426400D03*
G54D28*
X96457Y1747835D03*
Y1823031D03*
G54D10*
X-222440Y19685D03*
Y1948818D03*
X643700Y19685D03*
Y1948818D03*
G54D26*
X69800Y574200D03*
X180850Y348800D03*
X188500Y364100D03*
G54D27*
X69100Y698006D03*
X74100Y669398D03*
X78494Y697835D03*
X66000Y1149500D03*
X79044Y1144112D03*
X74000Y1132000D03*
X77293Y1129729D03*
X119000Y673300D03*
X124800Y696600D03*
X134100Y674500D03*
%LPC*%
G75*
G54D31*
G01X-448201Y-82763D02*
Y-162763D01*
G01Y-118263D02*
X752899D01*
G01X-448201Y-162763D02*
X752899D01*
G01X-452201Y-66763D02*
G02I-12000J0D01*
G01X-457351D02*
G02I-6850J0D01*
G01X-464201Y-82763D02*
Y-50763D01*
G01X-448201Y-66763D02*
X-480201D01*
G01X-448201Y-82763D02*
X752899D01*
G01X-34601D02*
Y-162763D01*
G01X102899Y-82763D02*
Y-162763D01*
G01X217899Y-82763D02*
Y-162763D01*
G01X385399Y-82763D02*
Y-162763D01*
G01X555399Y-82763D02*
Y-162763D01*
G01X752899Y-82763D02*
Y-162763D01*
G01X780899Y-66763D02*
G02I-12000J0D01*
G01X775749D02*
G02I-6850J0D01*
G01X768899Y-82763D02*
Y-50763D01*
G01X784899Y-66763D02*
X752899D01*
G54D32*
G01X-430254Y-152763D02*
Y-135263D01*
G01X-421958D02*
X-430254Y-146055D01*
G01X-420648Y-152763D02*
X-426543Y-141097D01*
G01X-412973Y-152763D02*
Y-135263D01*
X-402929Y-152763D01*
Y-135263D01*
G01X-390451Y-152763D02*
X-392198Y-152471D01*
X-393726Y-151305D01*
X-395036Y-149555D01*
X-395910Y-147513D01*
X-396346Y-145180D01*
Y-142846D01*
X-395910Y-140513D01*
X-395036Y-138471D01*
X-393726Y-136722D01*
X-392198Y-135555D01*
X-390451Y-135263D01*
X-388705Y-135555D01*
X-387176Y-136722D01*
X-385866Y-138471D01*
X-384992Y-140513D01*
X-384556Y-142846D01*
Y-145180D01*
X-384992Y-147513D01*
X-385866Y-149555D01*
X-387176Y-151305D01*
X-388705Y-152471D01*
X-390451Y-152763D01*
G01X-377536D02*
X-368366Y-135263D01*
G01X-377536D02*
X-368366Y-152763D01*
G01X-362001Y-158596D02*
X-348901D01*
G01X-342099Y-152763D02*
Y-135263D01*
X-333803D01*
G01X-336859Y-143721D02*
X-342099D01*
G01X-325910Y-152763D02*
X-320451Y-135263D01*
X-314992Y-152763D01*
G01X-316958Y-146638D02*
X-323945D01*
G01X-307973Y-152763D02*
Y-135263D01*
X-297929Y-152763D01*
Y-135263D01*
G01X-263148Y-136722D02*
X-264458Y-135846D01*
X-265986Y-135263D01*
X-267733D01*
X-269698Y-136138D01*
X-271226Y-137596D01*
X-272318Y-139347D01*
X-273191Y-142263D01*
X-273410Y-144888D01*
X-272973Y-147513D01*
X-272318Y-149263D01*
X-271008Y-151013D01*
X-269479Y-152180D01*
X-267951Y-152763D01*
X-266423D01*
X-264894Y-152180D01*
X-263584Y-151305D01*
X-262492Y-150139D01*
G01X-250451Y-152763D02*
X-252198Y-152471D01*
X-253726Y-151305D01*
X-255036Y-149555D01*
X-255910Y-147513D01*
X-256346Y-145180D01*
Y-142846D01*
X-255910Y-140513D01*
X-255036Y-138471D01*
X-253726Y-136722D01*
X-252198Y-135555D01*
X-250451Y-135263D01*
X-248705Y-135555D01*
X-247176Y-136722D01*
X-245866Y-138471D01*
X-244992Y-140513D01*
X-244556Y-142846D01*
Y-145180D01*
X-244992Y-147513D01*
X-245866Y-149555D01*
X-247176Y-151305D01*
X-248705Y-152471D01*
X-250451Y-152763D01*
G01X-237973D02*
Y-135263D01*
X-227929Y-152763D01*
Y-135263D01*
G01X-215451D02*
Y-152763D01*
G01X-220473Y-135263D02*
X-210429D01*
G01X-202318Y-152763D02*
Y-135263D01*
X-196859D01*
X-195113Y-136138D01*
X-194021Y-137305D01*
X-193584Y-139638D01*
X-194021Y-141972D01*
X-195331Y-143430D01*
X-196859Y-144305D01*
X-202318D01*
G01X-196859D02*
X-193584Y-152763D01*
G01X-180451D02*
X-182198Y-152471D01*
X-183726Y-151305D01*
X-185036Y-149555D01*
X-185910Y-147513D01*
X-186346Y-145180D01*
Y-142846D01*
X-185910Y-140513D01*
X-185036Y-138471D01*
X-183726Y-136722D01*
X-182198Y-135555D01*
X-180451Y-135263D01*
X-178705Y-135555D01*
X-177176Y-136722D01*
X-175866Y-138471D01*
X-174992Y-140513D01*
X-174556Y-142846D01*
Y-145180D01*
X-174992Y-147513D01*
X-175866Y-149555D01*
X-177176Y-151305D01*
X-178705Y-152471D01*
X-180451Y-152763D01*
G01X-167318Y-135263D02*
Y-152763D01*
X-158584D01*
G01X-126205Y-143430D02*
X-125331Y-142555D01*
X-124676Y-141097D01*
X-124239Y-139054D01*
X-124676Y-137305D01*
X-125549Y-136138D01*
X-127078Y-135263D01*
X-132973D01*
Y-152763D01*
X-125768D01*
X-124239Y-151597D01*
X-123366Y-149846D01*
X-122929Y-147805D01*
X-123366Y-145763D01*
X-124676Y-144013D01*
X-126205Y-143430D01*
X-132973D01*
G01X-110451Y-152763D02*
X-112198Y-152471D01*
X-113726Y-151305D01*
X-115036Y-149555D01*
X-115910Y-147513D01*
X-116346Y-145180D01*
Y-142846D01*
X-115910Y-140513D01*
X-115036Y-138471D01*
X-113726Y-136722D01*
X-112198Y-135555D01*
X-110451Y-135263D01*
X-108705Y-135555D01*
X-107176Y-136722D01*
X-105866Y-138471D01*
X-104992Y-140513D01*
X-104556Y-142846D01*
Y-145180D01*
X-104992Y-147513D01*
X-105866Y-149555D01*
X-107176Y-151305D01*
X-108705Y-152471D01*
X-110451Y-152763D01*
G01X-98410D02*
X-92951Y-135263D01*
X-87492Y-152763D01*
G01X-89458Y-146638D02*
X-96445D01*
G01X-79818Y-152763D02*
Y-135263D01*
X-74359D01*
X-72613Y-136138D01*
X-71521Y-137305D01*
X-71084Y-139638D01*
X-71521Y-141972D01*
X-72831Y-143430D01*
X-74359Y-144305D01*
X-79818D01*
G01X-74359D02*
X-71084Y-152763D01*
G01X-62754D02*
Y-135263D01*
X-58388D01*
X-56641Y-136138D01*
X-55331Y-137305D01*
X-54239Y-139054D01*
X-53366Y-141097D01*
X-53148Y-144013D01*
X-53366Y-146930D01*
X-54239Y-148972D01*
X-55331Y-150722D01*
X-56641Y-151888D01*
X-58388Y-152763D01*
X-62754D01*
G01X-282378Y-107763D02*
Y-90263D01*
X-276701Y-104846D01*
X-271024Y-90263D01*
Y-107763D01*
G01X-259201D02*
X-260511Y-107471D01*
X-261821Y-106305D01*
X-262695Y-104263D01*
X-263131Y-101930D01*
X-262695Y-99596D01*
X-261821Y-97555D01*
X-260511Y-96388D01*
X-259201Y-96097D01*
X-257891Y-96388D01*
X-256581Y-97555D01*
X-255708Y-99596D01*
X-255489Y-101930D01*
X-255708Y-104263D01*
X-256581Y-106305D01*
X-257891Y-107471D01*
X-259201Y-107763D01*
G01X-237771Y-90263D02*
Y-107763D01*
G01Y-105139D02*
X-238644Y-106597D01*
X-239955Y-107471D01*
X-241483Y-107763D01*
X-243229Y-107180D01*
X-244539Y-105722D01*
X-245413Y-103972D01*
X-245631Y-101930D01*
X-245413Y-99888D01*
X-244539Y-98138D01*
X-243229Y-96680D01*
X-241483Y-96097D01*
X-239955Y-96388D01*
X-238863Y-96972D01*
X-237771Y-98138D01*
G01X-227476Y-99888D02*
X-220489D01*
X-221144Y-97846D01*
X-222236Y-96680D01*
X-223764Y-96097D01*
X-225293Y-96388D01*
X-226603Y-97263D01*
X-227476Y-99305D01*
X-227913Y-101055D01*
Y-102805D01*
X-227476Y-104555D01*
X-226384Y-106305D01*
X-225074Y-107471D01*
X-223546Y-107763D01*
X-222018Y-107180D01*
X-220489Y-105430D01*
G01X-206701Y-107763D02*
Y-90263D01*
G01X-901Y-152763D02*
Y-135263D01*
X-3521Y-138763D01*
G01Y-152763D02*
X1719D01*
G01X12451Y-138180D02*
X13761Y-136430D01*
X15289Y-135555D01*
X17036Y-135263D01*
X19219Y-135846D01*
X20747Y-137305D01*
X21184Y-139054D01*
X20966Y-140805D01*
X20092Y-142263D01*
X15726Y-145180D01*
X13761Y-147221D01*
X12451Y-150139D01*
X12014Y-152763D01*
X21184D01*
G01X36719D02*
Y-135263D01*
X28640Y-147805D01*
X39558D01*
G01X46796Y-149263D02*
X48105Y-151305D01*
X49852Y-152471D01*
X51817Y-152763D01*
X53564Y-152471D01*
X55311Y-151013D01*
X56402Y-149263D01*
X56621Y-147513D01*
X56184Y-145472D01*
X54656Y-144013D01*
X53127Y-143430D01*
X51162D01*
G01X53127D02*
X54437Y-142555D01*
X55529Y-141097D01*
X55966Y-139347D01*
X55529Y-137596D01*
X54437Y-136138D01*
X52472Y-135263D01*
X50507Y-135555D01*
X48542Y-136722D01*
G01X64296Y-149263D02*
X65605Y-151305D01*
X67352Y-152471D01*
X69317Y-152763D01*
X71064Y-152471D01*
X72811Y-151013D01*
X73902Y-149263D01*
X74121Y-147513D01*
X73684Y-145472D01*
X72156Y-144013D01*
X70627Y-143430D01*
X68662D01*
G01X70627D02*
X71937Y-142555D01*
X73029Y-141097D01*
X73466Y-139347D01*
X73029Y-137596D01*
X71937Y-136138D01*
X69972Y-135263D01*
X68007Y-135555D01*
X66042Y-136722D01*
G01X-14018Y-107763D02*
Y-90263D01*
X-8778D01*
X-7031Y-91138D01*
X-5721Y-93180D01*
X-5284Y-95513D01*
X-5721Y-97846D01*
X-6813Y-99596D01*
X-8778Y-100472D01*
X-14018D01*
G01X12652Y-91722D02*
X11342Y-90846D01*
X9814Y-90263D01*
X8067D01*
X6102Y-91138D01*
X4574Y-92596D01*
X3482Y-94347D01*
X2609Y-97263D01*
X2390Y-99888D01*
X2827Y-102513D01*
X3482Y-104263D01*
X4792Y-106013D01*
X6321Y-107180D01*
X7849Y-107763D01*
X9377D01*
X10906Y-107180D01*
X12216Y-106305D01*
X13308Y-105139D01*
G01X27095Y-98430D02*
X27969Y-97555D01*
X28624Y-96097D01*
X29061Y-94054D01*
X28624Y-92305D01*
X27751Y-91138D01*
X26222Y-90263D01*
X20327D01*
Y-107763D01*
X27532D01*
X29061Y-106597D01*
X29934Y-104846D01*
X30371Y-102805D01*
X29934Y-100763D01*
X28624Y-99013D01*
X27095Y-98430D01*
X20327D01*
G01X36299Y-113596D02*
X49399D01*
G01X55327Y-107763D02*
Y-90263D01*
X65371Y-107763D01*
Y-90263D01*
G01X77849Y-107763D02*
X76102Y-107471D01*
X74574Y-106305D01*
X73264Y-104555D01*
X72390Y-102513D01*
X71954Y-100180D01*
Y-97846D01*
X72390Y-95513D01*
X73264Y-93471D01*
X74574Y-91722D01*
X76102Y-90555D01*
X77849Y-90263D01*
X79595Y-90555D01*
X81124Y-91722D01*
X82434Y-93471D01*
X83308Y-95513D01*
X83744Y-97846D01*
Y-100180D01*
X83308Y-102513D01*
X82434Y-104555D01*
X81124Y-106305D01*
X79595Y-107471D01*
X77849Y-107763D01*
G01X128690Y-90263D02*
X134149Y-107763D01*
X139608Y-90263D01*
G01X156016Y-107763D02*
X147282D01*
Y-90263D01*
X156016D01*
G01X152522Y-98721D02*
X147282D01*
G01X164782Y-107763D02*
Y-90263D01*
X170241D01*
X171987Y-91138D01*
X173079Y-92305D01*
X173516Y-94638D01*
X173079Y-96972D01*
X171769Y-98430D01*
X170241Y-99305D01*
X164782D01*
G01X170241D02*
X173516Y-107763D01*
G01X186649Y-108346D02*
X186212Y-108055D01*
Y-107471D01*
X186649Y-107180D01*
X187086Y-107471D01*
Y-108055D01*
X186649Y-108346D01*
G01X151649Y-152763D02*
Y-135263D01*
X149029Y-138763D01*
G01Y-152763D02*
X154269D01*
G01X163472D02*
Y-135263D01*
X169149Y-149846D01*
X174826Y-135263D01*
Y-152763D01*
G01X262232Y-135263D02*
Y-152763D01*
X270966D01*
G01X279951Y-138180D02*
X281261Y-136430D01*
X282789Y-135555D01*
X284536Y-135263D01*
X286719Y-135846D01*
X288247Y-137305D01*
X288684Y-139054D01*
X288466Y-140805D01*
X287592Y-142263D01*
X283226Y-145180D01*
X281261Y-147221D01*
X279951Y-150139D01*
X279514Y-152763D01*
X288684D01*
G01X302909Y-144013D02*
X307276D01*
Y-149263D01*
X305966Y-151013D01*
X304437Y-152180D01*
X302254Y-152763D01*
X300071Y-152180D01*
X298542Y-151013D01*
X297232Y-149263D01*
X296359Y-147221D01*
X295922Y-144888D01*
Y-142846D01*
X296359Y-141097D01*
X297232Y-139054D01*
X298542Y-137305D01*
X299852Y-136138D01*
X301599Y-135263D01*
X303127D01*
X304874Y-135846D01*
X306184Y-137013D01*
G01X314077Y-152763D02*
Y-135263D01*
X324121Y-152763D01*
Y-135263D01*
G01X331796Y-152763D02*
Y-135263D01*
X336162D01*
X337909Y-136138D01*
X339219Y-137305D01*
X340311Y-139054D01*
X341184Y-141097D01*
X341402Y-144013D01*
X341184Y-146930D01*
X340311Y-148972D01*
X339219Y-150722D01*
X337909Y-151888D01*
X336162Y-152763D01*
X331796D01*
G01X253482Y-90263D02*
Y-107763D01*
X262216D01*
G01X279279D02*
Y-96097D01*
G01Y-98138D02*
X278406Y-96972D01*
X277095Y-96388D01*
X275567Y-96097D01*
X274039Y-96680D01*
X272729Y-97846D01*
X271855Y-99596D01*
X271419Y-101930D01*
X271855Y-104263D01*
X272729Y-106013D01*
X274039Y-107180D01*
X275567Y-107763D01*
X277095Y-107471D01*
X278406Y-106597D01*
X279279Y-105430D01*
G01X288264Y-113013D02*
X289574Y-113596D01*
X291321Y-113013D01*
X292412Y-111847D01*
X293286Y-110388D01*
X294595Y-105722D01*
X297434Y-96097D01*
G01X290447D02*
X294595Y-105722D01*
G01X307074Y-99888D02*
X314061D01*
X313406Y-97846D01*
X312314Y-96680D01*
X310786Y-96097D01*
X309257Y-96388D01*
X307947Y-97263D01*
X307074Y-99305D01*
X306637Y-101055D01*
Y-102805D01*
X307074Y-104555D01*
X308166Y-106305D01*
X309476Y-107471D01*
X311004Y-107763D01*
X312532Y-107180D01*
X314061Y-105430D01*
G01X324792Y-107763D02*
Y-96097D01*
G01Y-98430D02*
X325884Y-97263D01*
X326976Y-96388D01*
X328504Y-96097D01*
X329595Y-96388D01*
X330906Y-97263D01*
G01X342074Y-105722D02*
X343166Y-106888D01*
X344694Y-107763D01*
X346004D01*
X347314Y-107180D01*
X348187Y-106305D01*
X348624Y-105139D01*
X348406Y-103388D01*
X347532Y-102513D01*
X343602Y-100763D01*
X342729Y-98721D01*
X343166Y-97263D01*
X344039Y-96388D01*
X345349Y-96097D01*
X346659Y-96388D01*
X347969Y-97263D01*
G01X404346Y-107763D02*
Y-90263D01*
X408712D01*
X410459Y-91138D01*
X411769Y-92305D01*
X412861Y-94054D01*
X413734Y-96097D01*
X413952Y-99013D01*
X413734Y-101930D01*
X412861Y-103972D01*
X411769Y-105722D01*
X410459Y-106888D01*
X408712Y-107763D01*
X404346D01*
G01X423374Y-99888D02*
X430361D01*
X429706Y-97846D01*
X428614Y-96680D01*
X427086Y-96097D01*
X425557Y-96388D01*
X424247Y-97263D01*
X423374Y-99305D01*
X422937Y-101055D01*
Y-102805D01*
X423374Y-104555D01*
X424466Y-106305D01*
X425776Y-107471D01*
X427304Y-107763D01*
X428832Y-107180D01*
X430361Y-105430D01*
G01X440874Y-105722D02*
X441966Y-106888D01*
X443494Y-107763D01*
X444804D01*
X446114Y-107180D01*
X446987Y-106305D01*
X447424Y-105139D01*
X447206Y-103388D01*
X446332Y-102513D01*
X442402Y-100763D01*
X441529Y-98721D01*
X441966Y-97263D01*
X442839Y-96388D01*
X444149Y-96097D01*
X445459Y-96388D01*
X446769Y-97263D01*
G01X461649Y-96097D02*
Y-107763D01*
G01Y-91430D02*
X461212Y-91138D01*
Y-90555D01*
X461649Y-90263D01*
X462086Y-90555D01*
Y-91138D01*
X461649Y-91430D01*
G01X476092Y-112138D02*
X477621Y-113305D01*
X479367Y-113596D01*
X480895Y-113305D01*
X482206Y-111847D01*
X483079Y-109805D01*
Y-96097D01*
G01Y-98430D02*
X482206Y-97263D01*
X480895Y-96388D01*
X479367Y-96097D01*
X477621Y-96680D01*
X476529Y-97846D01*
X475655Y-99888D01*
X475219Y-101930D01*
X475437Y-103680D01*
X476311Y-105722D01*
X477621Y-107180D01*
X479367Y-107763D01*
X480677Y-107471D01*
X482206Y-106305D01*
X483079Y-105139D01*
G01X492937Y-107763D02*
Y-96097D01*
G01Y-99013D02*
X493811Y-97555D01*
X495121Y-96388D01*
X496867Y-96097D01*
X498395Y-96388D01*
X499706Y-97555D01*
X500361Y-99596D01*
Y-107763D01*
G01X510874Y-99888D02*
X517861D01*
X517206Y-97846D01*
X516114Y-96680D01*
X514586Y-96097D01*
X513057Y-96388D01*
X511747Y-97263D01*
X510874Y-99305D01*
X510437Y-101055D01*
Y-102805D01*
X510874Y-104555D01*
X511966Y-106305D01*
X513276Y-107471D01*
X514804Y-107763D01*
X516332Y-107180D01*
X517861Y-105430D01*
G01X528592Y-107763D02*
Y-96097D01*
G01Y-98430D02*
X529684Y-97263D01*
X530776Y-96388D01*
X532304Y-96097D01*
X533395Y-96388D01*
X534706Y-97263D01*
G01X448096Y-152763D02*
Y-135263D01*
X452462D01*
X454209Y-136138D01*
X455519Y-137305D01*
X456611Y-139054D01*
X457484Y-141097D01*
X457702Y-144013D01*
X457484Y-146930D01*
X456611Y-148972D01*
X455519Y-150722D01*
X454209Y-151888D01*
X452462Y-152763D01*
X448096D01*
G01X470399Y-141097D02*
Y-152763D01*
G01Y-136430D02*
X469962Y-136138D01*
Y-135555D01*
X470399Y-135263D01*
X470836Y-135555D01*
Y-136138D01*
X470399Y-136430D01*
G01X487899Y-152763D02*
X486589Y-152471D01*
X485279Y-151305D01*
X484405Y-149263D01*
X483969Y-146930D01*
X484405Y-144596D01*
X485279Y-142555D01*
X486589Y-141388D01*
X487899Y-141097D01*
X489209Y-141388D01*
X490519Y-142555D01*
X491392Y-144596D01*
X491611Y-146930D01*
X491392Y-149263D01*
X490519Y-151305D01*
X489209Y-152471D01*
X487899Y-152763D01*
G01X575349D02*
Y-135263D01*
X572729Y-138763D01*
G01Y-152763D02*
X577969D01*
G01X588701Y-138180D02*
X590011Y-136430D01*
X591539Y-135555D01*
X593286Y-135263D01*
X595469Y-135846D01*
X596997Y-137305D01*
X597434Y-139054D01*
X597216Y-140805D01*
X596342Y-142263D01*
X591976Y-145180D01*
X590011Y-147221D01*
X588701Y-150139D01*
X588264Y-152763D01*
X597434D01*
G01X606419Y-153346D02*
X614279Y-135263D01*
G01X627849D02*
X626102Y-135846D01*
X624792Y-137305D01*
X623919Y-139054D01*
X623264Y-141388D01*
X623046Y-144013D01*
X623264Y-146638D01*
X623919Y-148972D01*
X624792Y-150722D01*
X626102Y-152180D01*
X627849Y-152763D01*
X629595Y-152180D01*
X630906Y-150722D01*
X631779Y-148972D01*
X632434Y-146638D01*
X632652Y-144013D01*
X632434Y-141388D01*
X631779Y-139054D01*
X630906Y-137305D01*
X629595Y-135846D01*
X627849Y-135263D01*
G01X644912Y-152763D02*
X645349Y-148972D01*
X646004Y-145763D01*
X646877Y-142846D01*
X647969Y-139638D01*
X649716Y-135263D01*
X640982D01*
G01X658919Y-153346D02*
X666779Y-135263D01*
G01X676201Y-138180D02*
X677511Y-136430D01*
X679039Y-135555D01*
X680786Y-135263D01*
X682969Y-135846D01*
X684497Y-137305D01*
X684934Y-139054D01*
X684716Y-140805D01*
X683842Y-142263D01*
X679476Y-145180D01*
X677511Y-147221D01*
X676201Y-150139D01*
X675764Y-152763D01*
X684934D01*
G01X697849Y-135263D02*
X696102Y-135846D01*
X694792Y-137305D01*
X693919Y-139054D01*
X693264Y-141388D01*
X693046Y-144013D01*
X693264Y-146638D01*
X693919Y-148972D01*
X694792Y-150722D01*
X696102Y-152180D01*
X697849Y-152763D01*
X699595Y-152180D01*
X700906Y-150722D01*
X701779Y-148972D01*
X702434Y-146638D01*
X702652Y-144013D01*
X702434Y-141388D01*
X701779Y-139054D01*
X700906Y-137305D01*
X699595Y-135846D01*
X697849Y-135263D01*
G01X715349Y-152763D02*
Y-135263D01*
X712729Y-138763D01*
G01Y-152763D02*
X717969D01*
G01X728701Y-138180D02*
X730011Y-136430D01*
X731539Y-135555D01*
X733286Y-135263D01*
X735469Y-135846D01*
X736997Y-137305D01*
X737434Y-139054D01*
X737216Y-140805D01*
X736342Y-142263D01*
X731976Y-145180D01*
X730011Y-147221D01*
X728701Y-150139D01*
X728264Y-152763D01*
X737434D01*
G01X623046Y-107763D02*
Y-90263D01*
X627412D01*
X629159Y-91138D01*
X630469Y-92305D01*
X631561Y-94054D01*
X632434Y-96097D01*
X632652Y-99013D01*
X632434Y-101930D01*
X631561Y-103972D01*
X630469Y-105722D01*
X629159Y-106888D01*
X627412Y-107763D01*
X623046D01*
G01X649279D02*
Y-96097D01*
G01Y-98138D02*
X648406Y-96972D01*
X647095Y-96388D01*
X645567Y-96097D01*
X644039Y-96680D01*
X642729Y-97846D01*
X641855Y-99596D01*
X641419Y-101930D01*
X641855Y-104263D01*
X642729Y-106013D01*
X644039Y-107180D01*
X645567Y-107763D01*
X647095Y-107471D01*
X648406Y-106597D01*
X649279Y-105430D01*
G01X662849Y-90263D02*
Y-107763D01*
G01X659792Y-96097D02*
X665906D01*
G01X677074Y-99888D02*
X684061D01*
X683406Y-97846D01*
X682314Y-96680D01*
X680786Y-96097D01*
X679257Y-96388D01*
X677947Y-97263D01*
X677074Y-99305D01*
X676637Y-101055D01*
Y-102805D01*
X677074Y-104555D01*
X678166Y-106305D01*
X679476Y-107471D01*
X681004Y-107763D01*
X682532Y-107180D01*
X684061Y-105430D01*
M02*
